FILE_TYPE = MACRO_DRAWING;
SET COLOR_WIRE YELLOW;
SET COLOR_PROP ORANGE;
SET COLOR_DOT WHITE;
SET COLOR_ARC YELLOW;
SET COLOR_BODY GREEN;
SET COLOR_NOTE PURPLE;
SET PROP_DISPLAY VALUE;
SET PAGE_NUMBER P320;
FORCEADD OFFPAGE..1
(-3150 -900);
FORCEPROP 2 LAST $XR0 287 
J 0
(-3402 -900);
DISPLAY 0.638298 (-3402 -900);
PAINT MONO (-3402 -900);
FORCEPROP 2 LAST CDS_LIB standard
J 0
(-3150 -900);
DISPLAY INVISIBLE (-3150 -900);
FORCEPROP 1 LAST OFFPAGE TRUE
J 0
(-2825 -1025);
DISPLAY 0.872340 (-2825 -1025);
PAINT AQUA (-2825 -1025);
DISPLAY INVISIBLE (-2825 -1025);
FORCEPROP 1 LAST COMMENT_BODY TRUE
J 0
(-3025 -1000);
DISPLAY 0.872340 (-3025 -1000);
PAINT GREEN (-3025 -1000);
DISPLAY INVISIBLE (-3025 -1000);
FORCEPROP 2 LAST PATH I1
J 0
(-3400 -850);
DISPLAY 0.680851 (-3400 -850);
DISPLAY INVISIBLE (-3400 -850);
FORCEADD OFFPAGE..1
(-3150 -50);
FORCEPROP 2 LAST $XR0 287 
J 0
(-3402 -50);
DISPLAY 0.638298 (-3402 -50);
PAINT MONO (-3402 -50);
FORCEPROP 2 LAST CDS_LIB standard
J 0
(-3150 -50);
DISPLAY INVISIBLE (-3150 -50);
FORCEPROP 1 LAST OFFPAGE TRUE
J 0
(-2825 -175);
DISPLAY 0.872340 (-2825 -175);
PAINT AQUA (-2825 -175);
DISPLAY INVISIBLE (-2825 -175);
FORCEPROP 1 LAST COMMENT_BODY TRUE
J 0
(-3025 -150);
DISPLAY 0.872340 (-3025 -150);
PAINT GREEN (-3025 -150);
DISPLAY INVISIBLE (-3025 -150);
FORCEPROP 2 LAST PATH I10
J 0
(-3400 0);
DISPLAY 0.680851 (-3400 0);
DISPLAY INVISIBLE (-3400 0);
FORCEADD OFFPAGE..1
(-3150 0);
FORCEPROP 2 LAST $XR0 287 
J 0
(-3402 0);
DISPLAY 0.638298 (-3402 0);
PAINT MONO (-3402 0);
FORCEPROP 2 LAST CDS_LIB standard
J 0
(-3150 0);
DISPLAY INVISIBLE (-3150 0);
FORCEPROP 1 LAST OFFPAGE TRUE
J 0
(-2825 -125);
DISPLAY 0.872340 (-2825 -125);
PAINT AQUA (-2825 -125);
DISPLAY INVISIBLE (-2825 -125);
FORCEPROP 1 LAST COMMENT_BODY TRUE
J 0
(-3025 -100);
DISPLAY 0.872340 (-3025 -100);
PAINT GREEN (-3025 -100);
DISPLAY INVISIBLE (-3025 -100);
FORCEPROP 2 LAST PATH I11
J 0
(-3400 50);
DISPLAY 0.680851 (-3400 50);
DISPLAY INVISIBLE (-3400 50);
FORCEADD OFFPAGE..1
(-3150 100);
FORCEPROP 2 LAST $XR0 276 
J 0
(-3402 100);
DISPLAY 0.638298 (-3402 100);
PAINT MONO (-3402 100);
FORCEPROP 2 LAST CDS_LIB standard
J 0
(-3150 100);
DISPLAY INVISIBLE (-3150 100);
FORCEPROP 1 LAST OFFPAGE TRUE
J 0
(-2825 -25);
DISPLAY 0.872340 (-2825 -25);
PAINT AQUA (-2825 -25);
DISPLAY INVISIBLE (-2825 -25);
FORCEPROP 1 LAST COMMENT_BODY TRUE
J 0
(-3025 0);
DISPLAY 0.872340 (-3025 0);
PAINT GREEN (-3025 0);
DISPLAY INVISIBLE (-3025 0);
FORCEPROP 2 LAST PATH I12
J 0
(-3400 150);
DISPLAY 0.680851 (-3400 150);
DISPLAY INVISIBLE (-3400 150);
FORCEADD OFFPAGE..1
(-3150 150);
FORCEPROP 2 LAST $XR0 276 
J 0
(-3402 150);
DISPLAY 0.638298 (-3402 150);
PAINT MONO (-3402 150);
FORCEPROP 2 LAST CDS_LIB standard
J 0
(-3150 150);
DISPLAY INVISIBLE (-3150 150);
FORCEPROP 1 LAST OFFPAGE TRUE
J 0
(-2825 25);
DISPLAY 0.872340 (-2825 25);
PAINT AQUA (-2825 25);
DISPLAY INVISIBLE (-2825 25);
FORCEPROP 1 LAST COMMENT_BODY TRUE
J 0
(-3025 50);
DISPLAY 0.872340 (-3025 50);
PAINT GREEN (-3025 50);
DISPLAY INVISIBLE (-3025 50);
FORCEPROP 2 LAST PATH I13
J 0
(-3400 200);
DISPLAY 0.680851 (-3400 200);
DISPLAY INVISIBLE (-3400 200);
FORCEADD UNIVERSAL_GND..1
(-2050 -1300);
FORCEPROP 3 LASTPIN (-2050 -1250) SIG_NAME GND\g
J 0
(-2040 -1240);
DISPLAY 0.659574 (-2040 -1240);
PAINT MONO (-2040 -1240);
DISPLAY INVISIBLE (-2040 -1240);
FORCEPROP 2 LAST CDS_LIB pure_quanta_power
J 0
(-2050 -1300);
DISPLAY INVISIBLE (-2050 -1300);
FORCEPROP 1 LAST HDL_POWER GND
J 1
(-2025 -1375);
DISPLAY 0.872340 (-2025 -1375);
PAINT GREEN (-2025 -1375);
DISPLAY INVISIBLE (-2025 -1375);
FORCEPROP 1 LAST PATH I14
J 0
(-1975 -1300);
DISPLAY 0.872340 (-1975 -1300);
PAINT AQUA (-1975 -1300);
DISPLAY INVISIBLE (-1975 -1300);
FORCEADD CONN112_10137002101LF..1
(-950 600);
FORCEPROP 1 LAST LOCATION J108
J 0
(-1700 2400);
DISPLAY 0.723404 (-1700 2400);
PAINT GREEN (-1700 2400);
FORCEPROP 0 LAST $SEC 1
J 0
(-1700 2525);
DISPLAY 0.680851 (-1700 2525);
PAINT MONO (-1700 2525);
DISPLAY INVISIBLE (-1700 2525);
FORCEPROP 0 LAST CDS_SEC 1
J 0
(-1700 2525);
DISPLAY 1.021277 (-1700 2525);
DISPLAY INVISIBLE (-1700 2525);
FORCEPROP 0 LASTPIN (-1875 -300) $PN A5
J 2
(-1885 -290);
DISPLAY 0.680851 (-1885 -290);
PAINT MONO (-1885 -290);
FORCEPROP 0 LASTPIN (-1875 500) $PN A6
J 2
(-1885 510);
DISPLAY 0.680851 (-1885 510);
PAINT MONO (-1885 510);
FORCEPROP 0 LASTPIN (-1875 1300) $PN A7
J 2
(-1885 1310);
DISPLAY 0.680851 (-1885 1310);
PAINT MONO (-1885 1310);
FORCEPROP 0 LASTPIN (-1875 2100) $PN A8
J 2
(-1885 2110);
DISPLAY 0.680851 (-1885 2110);
PAINT MONO (-1885 2110);
FORCEPROP 0 LASTPIN (-1875 -350) $PN B5
J 2
(-1885 -340);
DISPLAY 0.680851 (-1885 -340);
PAINT MONO (-1885 -340);
FORCEPROP 0 LASTPIN (-1875 450) $PN B6
J 2
(-1885 460);
DISPLAY 0.680851 (-1885 460);
PAINT MONO (-1885 460);
FORCEPROP 0 LASTPIN (-1875 1250) $PN B7
J 2
(-1885 1260);
DISPLAY 0.680851 (-1885 1260);
PAINT MONO (-1885 1260);
FORCEPROP 0 LASTPIN (-1875 2050) $PN B8
J 2
(-1885 2060);
DISPLAY 0.680851 (-1885 2060);
PAINT MONO (-1885 2060);
FORCEPROP 0 LASTPIN (-1875 -400) $PN C5
J 2
(-1885 -390);
DISPLAY 0.680851 (-1885 -390);
PAINT MONO (-1885 -390);
FORCEPROP 0 LASTPIN (-1875 400) $PN C6
J 2
(-1885 410);
DISPLAY 0.680851 (-1885 410);
PAINT MONO (-1885 410);
FORCEPROP 0 LASTPIN (-1875 1200) $PN C7
J 2
(-1885 1210);
DISPLAY 0.680851 (-1885 1210);
PAINT MONO (-1885 1210);
FORCEPROP 0 LASTPIN (-1875 2000) $PN C8
J 2
(-1885 2010);
DISPLAY 0.680851 (-1885 2010);
PAINT MONO (-1885 2010);
FORCEPROP 0 LASTPIN (-1875 -450) $PN D5
J 2
(-1885 -440);
DISPLAY 0.680851 (-1885 -440);
PAINT MONO (-1885 -440);
FORCEPROP 0 LASTPIN (-1875 350) $PN D6
J 2
(-1885 360);
DISPLAY 0.680851 (-1885 360);
PAINT MONO (-1885 360);
FORCEPROP 0 LASTPIN (-1875 1150) $PN D7
J 2
(-1885 1160);
DISPLAY 0.680851 (-1885 1160);
PAINT MONO (-1885 1160);
FORCEPROP 0 LASTPIN (-1875 1950) $PN D8
J 2
(-1885 1960);
DISPLAY 0.680851 (-1885 1960);
PAINT MONO (-1885 1960);
FORCEPROP 0 LASTPIN (-1875 -500) $PN E5
J 2
(-1885 -490);
DISPLAY 0.680851 (-1885 -490);
PAINT MONO (-1885 -490);
FORCEPROP 0 LASTPIN (-1875 300) $PN E6
J 2
(-1885 310);
DISPLAY 0.680851 (-1885 310);
PAINT MONO (-1885 310);
FORCEPROP 0 LASTPIN (-1875 1100) $PN E7
J 2
(-1885 1110);
DISPLAY 0.680851 (-1885 1110);
PAINT MONO (-1885 1110);
FORCEPROP 0 LASTPIN (-1875 1900) $PN E8
J 2
(-1885 1910);
DISPLAY 0.680851 (-1885 1910);
PAINT MONO (-1885 1910);
FORCEPROP 0 LASTPIN (-1875 -550) $PN F5
J 2
(-1885 -540);
DISPLAY 0.680851 (-1885 -540);
PAINT MONO (-1885 -540);
FORCEPROP 0 LASTPIN (-1875 250) $PN F6
J 2
(-1885 260);
DISPLAY 0.680851 (-1885 260);
PAINT MONO (-1885 260);
FORCEPROP 0 LASTPIN (-1875 1050) $PN F7
J 2
(-1885 1060);
DISPLAY 0.680851 (-1885 1060);
PAINT MONO (-1885 1060);
FORCEPROP 0 LASTPIN (-1875 1850) $PN F8
J 2
(-1885 1860);
DISPLAY 0.680851 (-1885 1860);
PAINT MONO (-1885 1860);
FORCEPROP 0 LASTPIN (-1875 -600) $PN G5
J 2
(-1885 -590);
DISPLAY 0.680851 (-1885 -590);
PAINT MONO (-1885 -590);
FORCEPROP 0 LASTPIN (-1875 200) $PN G6
J 2
(-1885 210);
DISPLAY 0.680851 (-1885 210);
PAINT MONO (-1885 210);
FORCEPROP 0 LASTPIN (-1875 1000) $PN G7
J 2
(-1885 1010);
DISPLAY 0.680851 (-1885 1010);
PAINT MONO (-1885 1010);
FORCEPROP 0 LASTPIN (-1875 1800) $PN G8
J 2
(-1885 1810);
DISPLAY 0.680851 (-1885 1810);
PAINT MONO (-1885 1810);
FORCEPROP 0 LASTPIN (-1875 -650) $PN H5
J 2
(-1885 -640);
DISPLAY 0.680851 (-1885 -640);
PAINT MONO (-1885 -640);
FORCEPROP 0 LASTPIN (-1875 150) $PN H6
J 2
(-1885 160);
DISPLAY 0.680851 (-1885 160);
PAINT MONO (-1885 160);
FORCEPROP 0 LASTPIN (-1875 950) $PN H7
J 2
(-1885 960);
DISPLAY 0.680851 (-1885 960);
PAINT MONO (-1885 960);
FORCEPROP 0 LASTPIN (-1875 1750) $PN H8
J 2
(-1885 1760);
DISPLAY 0.680851 (-1885 1760);
PAINT MONO (-1885 1760);
FORCEPROP 0 LASTPIN (-1875 -700) $PN I5
J 2
(-1885 -690);
DISPLAY 0.680851 (-1885 -690);
PAINT MONO (-1885 -690);
FORCEPROP 0 LASTPIN (-1875 100) $PN I6
J 2
(-1885 110);
DISPLAY 0.680851 (-1885 110);
PAINT MONO (-1885 110);
FORCEPROP 0 LASTPIN (-1875 900) $PN I7
J 2
(-1885 910);
DISPLAY 0.680851 (-1885 910);
PAINT MONO (-1885 910);
FORCEPROP 0 LASTPIN (-1875 1700) $PN I8
J 2
(-1885 1710);
DISPLAY 0.680851 (-1885 1710);
PAINT MONO (-1885 1710);
FORCEPROP 0 LASTPIN (-1875 -750) $PN J5
J 2
(-1885 -740);
DISPLAY 0.680851 (-1885 -740);
PAINT MONO (-1885 -740);
FORCEPROP 0 LASTPIN (-1875 50) $PN J6
J 2
(-1885 60);
DISPLAY 0.680851 (-1885 60);
PAINT MONO (-1885 60);
FORCEPROP 0 LASTPIN (-1875 850) $PN J7
J 2
(-1885 860);
DISPLAY 0.680851 (-1885 860);
PAINT MONO (-1885 860);
FORCEPROP 0 LASTPIN (-1875 1650) $PN J8
J 2
(-1885 1660);
DISPLAY 0.680851 (-1885 1660);
PAINT MONO (-1885 1660);
FORCEPROP 0 LASTPIN (-1875 -800) $PN K5
J 2
(-1885 -790);
DISPLAY 0.680851 (-1885 -790);
PAINT MONO (-1885 -790);
FORCEPROP 0 LASTPIN (-1875 0) $PN K6
J 2
(-1885 10);
DISPLAY 0.680851 (-1885 10);
PAINT MONO (-1885 10);
FORCEPROP 0 LASTPIN (-1875 800) $PN K7
J 2
(-1885 810);
DISPLAY 0.680851 (-1885 810);
PAINT MONO (-1885 810);
FORCEPROP 0 LASTPIN (-1875 1600) $PN K8
J 2
(-1885 1610);
DISPLAY 0.680851 (-1885 1610);
PAINT MONO (-1885 1610);
FORCEPROP 0 LASTPIN (-1875 -850) $PN L5
J 2
(-1885 -840);
DISPLAY 0.680851 (-1885 -840);
PAINT MONO (-1885 -840);
FORCEPROP 0 LASTPIN (-1875 -50) $PN L6
J 2
(-1885 -40);
DISPLAY 0.680851 (-1885 -40);
PAINT MONO (-1885 -40);
FORCEPROP 0 LASTPIN (-1875 750) $PN L7
J 2
(-1885 760);
DISPLAY 0.680851 (-1885 760);
PAINT MONO (-1885 760);
FORCEPROP 0 LASTPIN (-1875 1550) $PN L8
J 2
(-1885 1560);
DISPLAY 0.680851 (-1885 1560);
PAINT MONO (-1885 1560);
FORCEPROP 0 LASTPIN (-1875 -900) $PN M5
J 2
(-1885 -890);
DISPLAY 0.680851 (-1885 -890);
PAINT MONO (-1885 -890);
FORCEPROP 0 LASTPIN (-1875 -100) $PN M6
J 2
(-1885 -90);
DISPLAY 0.680851 (-1885 -90);
PAINT MONO (-1885 -90);
FORCEPROP 0 LASTPIN (-1875 700) $PN M7
J 2
(-1885 710);
DISPLAY 0.680851 (-1885 710);
PAINT MONO (-1885 710);
FORCEPROP 0 LASTPIN (-1875 1500) $PN M8
J 2
(-1885 1510);
DISPLAY 0.680851 (-1885 1510);
PAINT MONO (-1885 1510);
FORCEPROP 0 LASTPIN (-1875 -950) $PN N5
J 2
(-1885 -940);
DISPLAY 0.680851 (-1885 -940);
PAINT MONO (-1885 -940);
FORCEPROP 0 LASTPIN (-1875 -150) $PN N6
J 2
(-1885 -140);
DISPLAY 0.680851 (-1885 -140);
PAINT MONO (-1885 -140);
FORCEPROP 0 LASTPIN (-1875 650) $PN N7
J 2
(-1885 660);
DISPLAY 0.680851 (-1885 660);
PAINT MONO (-1885 660);
FORCEPROP 0 LASTPIN (-1875 1450) $PN N8
J 2
(-1885 1460);
DISPLAY 0.680851 (-1885 1460);
PAINT MONO (-1885 1460);
FORCEPROP 1 LAST MATERIAL IO
J 0
(-1695 2282);
DISPLAY 0.723404 (-1695 2282);
PAINT GREEN (-1695 2282);
FORCEPROP 2 LAST PART_TYPE THLF
J 0
(-1700 2475);
DISPLAY 1.021277 (-1700 2475);
FORCEPROP 0 LAST VALUE CONN112_10137002-101LF
J 0
(-1675 2600);
DISPLAY 1.021277 (-1675 2600);
DISPLAY INVISIBLE (-1675 2600);
FORCEPROP 1 LAST CDS_LMAN_SYM_OUTLINE -775,1650,775,-1650
J 0
(-950 600);
DISPLAY 0.468085 (-950 600);
PAINT GREEN (-950 600);
DISPLAY INVISIBLE (-950 600);
FORCEPROP 1 LAST NEEDS_NO_SIZE TRUE
J 0
(-950 600);
DISPLAY 0.723404 (-950 600);
PAINT GREEN (-950 600);
DISPLAY INVISIBLE (-950 600);
FORCEPROP 2 LAST CDS_LIB pure_quanta
J 0
(-950 600);
DISPLAY INVISIBLE (-950 600);
FORCEPROP 1 LAST PATH I15
J 0
(-950 600);
DISPLAY 0.723404 (-950 600);
PAINT GREEN (-950 600);
DISPLAY INVISIBLE (-950 600);
FORCEPROP 1 LAST PART_NUMBER DFHSB2FR012
J 0
(-1700 2350);
DISPLAY 0.723404 (-1700 2350);
PAINT GREEN (-1700 2350);
DISPLAY INVISIBLE (-1700 2350);
FORCEADD OFFPAGE..2
R 2
(-3150 300);
FORCEPROP 2 LAST $XR0 286 
J 0
(-3405 300);
DISPLAY 0.638298 (-3405 300);
PAINT MONO (-3405 300);
FORCEPROP 2 LAST CDS_LIB standard
J 0
(-3150 300);
DISPLAY INVISIBLE (-3150 300);
FORCEPROP 1 LAST OFFPAGE TRUE
J 2
(-3475 175);
DISPLAY 0.872340 (-3475 175);
PAINT AQUA (-3475 175);
DISPLAY INVISIBLE (-3475 175);
FORCEPROP 1 LAST COMMENT_BODY TRUE
J 2
(-3105 205);
DISPLAY 0.872340 (-3105 205);
PAINT GREEN (-3105 205);
DISPLAY INVISIBLE (-3105 205);
FORCEPROP 2 LAST PATH I16
J 0
(-3425 350);
DISPLAY 0.680851 (-3425 350);
DISPLAY INVISIBLE (-3425 350);
FORCEADD OFFPAGE..5
(-3150 250);
FORCEPROP 2 LAST $XR0 286 
J 0
(-3405 250);
DISPLAY 0.638298 (-3405 250);
PAINT MONO (-3405 250);
FORCEPROP 2 LAST CDS_LIB standard
J 0
(-3150 250);
DISPLAY INVISIBLE (-3150 250);
FORCEPROP 1 LAST OFFPAGE TRUE
J 0
(-2825 125);
DISPLAY 0.872340 (-2825 125);
PAINT AQUA (-2825 125);
DISPLAY INVISIBLE (-2825 125);
FORCEPROP 1 LAST COMMENT_BODY TRUE
J 0
(-3050 175);
DISPLAY 1.170213 (-3050 175);
PAINT GREEN (-3050 175);
DISPLAY INVISIBLE (-3050 175);
FORCEPROP 2 LAST PATH I17
J 0
(-3425 300);
DISPLAY 0.680851 (-3425 300);
DISPLAY INVISIBLE (-3425 300);
FORCEADD OFFPAGE..5
(-3150 400);
FORCEPROP 2 LAST $XR0 275 
J 0
(-3405 400);
DISPLAY 0.638298 (-3405 400);
PAINT MONO (-3405 400);
FORCEPROP 2 LAST CDS_LIB standard
J 0
(-3150 400);
DISPLAY INVISIBLE (-3150 400);
FORCEPROP 1 LAST OFFPAGE TRUE
J 0
(-2825 275);
DISPLAY 0.872340 (-2825 275);
PAINT AQUA (-2825 275);
DISPLAY INVISIBLE (-2825 275);
FORCEPROP 1 LAST COMMENT_BODY TRUE
J 0
(-3050 325);
DISPLAY 1.170213 (-3050 325);
PAINT GREEN (-3050 325);
DISPLAY INVISIBLE (-3050 325);
FORCEPROP 2 LAST PATH I18
J 0
(-3425 450);
DISPLAY 0.680851 (-3425 450);
DISPLAY INVISIBLE (-3425 450);
FORCEADD OFFPAGE..2
R 2
(-3150 450);
FORCEPROP 2 LAST $XR0 275 
J 0
(-3405 450);
DISPLAY 0.638298 (-3405 450);
PAINT MONO (-3405 450);
FORCEPROP 2 LAST CDS_LIB standard
J 0
(-3150 450);
DISPLAY INVISIBLE (-3150 450);
FORCEPROP 1 LAST OFFPAGE TRUE
J 2
(-3475 325);
DISPLAY 0.872340 (-3475 325);
PAINT AQUA (-3475 325);
DISPLAY INVISIBLE (-3475 325);
FORCEPROP 1 LAST COMMENT_BODY TRUE
J 2
(-3105 355);
DISPLAY 0.872340 (-3105 355);
PAINT GREEN (-3105 355);
DISPLAY INVISIBLE (-3105 355);
FORCEPROP 2 LAST PATH I19
J 0
(-3425 500);
DISPLAY 0.680851 (-3425 500);
DISPLAY INVISIBLE (-3425 500);
FORCEADD OFFPAGE..1
(-3150 -850);
FORCEPROP 2 LAST $XR0 287 
J 0
(-3402 -850);
DISPLAY 0.638298 (-3402 -850);
PAINT MONO (-3402 -850);
FORCEPROP 2 LAST CDS_LIB standard
J 0
(-3150 -850);
DISPLAY INVISIBLE (-3150 -850);
FORCEPROP 1 LAST OFFPAGE TRUE
J 0
(-2825 -975);
DISPLAY 0.872340 (-2825 -975);
PAINT AQUA (-2825 -975);
DISPLAY INVISIBLE (-2825 -975);
FORCEPROP 1 LAST COMMENT_BODY TRUE
J 0
(-3025 -950);
DISPLAY 0.872340 (-3025 -950);
PAINT GREEN (-3025 -950);
DISPLAY INVISIBLE (-3025 -950);
FORCEPROP 2 LAST PATH I2
J 0
(-3400 -800);
DISPLAY 0.680851 (-3400 -800);
DISPLAY INVISIBLE (-3400 -800);
FORCEADD OFFPAGE..1
(-3150 700);
FORCEPROP 2 LAST $XR0 287 
J 0
(-3402 700);
DISPLAY 0.638298 (-3402 700);
PAINT MONO (-3402 700);
FORCEPROP 2 LAST CDS_LIB standard
J 0
(-3150 700);
DISPLAY INVISIBLE (-3150 700);
FORCEPROP 1 LAST OFFPAGE TRUE
J 0
(-2825 575);
DISPLAY 0.872340 (-2825 575);
PAINT AQUA (-2825 575);
DISPLAY INVISIBLE (-2825 575);
FORCEPROP 1 LAST COMMENT_BODY TRUE
J 0
(-3025 600);
DISPLAY 0.872340 (-3025 600);
PAINT GREEN (-3025 600);
DISPLAY INVISIBLE (-3025 600);
FORCEPROP 2 LAST PATH I20
J 0
(-3400 750);
DISPLAY 0.680851 (-3400 750);
DISPLAY INVISIBLE (-3400 750);
FORCEADD OFFPAGE..1
(-3150 750);
FORCEPROP 2 LAST $XR0 287 
J 0
(-3402 750);
DISPLAY 0.638298 (-3402 750);
PAINT MONO (-3402 750);
FORCEPROP 2 LAST CDS_LIB standard
J 0
(-3150 750);
DISPLAY INVISIBLE (-3150 750);
FORCEPROP 1 LAST OFFPAGE TRUE
J 0
(-2825 625);
DISPLAY 0.872340 (-2825 625);
PAINT AQUA (-2825 625);
DISPLAY INVISIBLE (-2825 625);
FORCEPROP 1 LAST COMMENT_BODY TRUE
J 0
(-3025 650);
DISPLAY 0.872340 (-3025 650);
PAINT GREEN (-3025 650);
DISPLAY INVISIBLE (-3025 650);
FORCEPROP 2 LAST PATH I21
J 0
(-3400 800);
DISPLAY 0.680851 (-3400 800);
DISPLAY INVISIBLE (-3400 800);
FORCEADD OFFPAGE..1
(-3150 850);
FORCEPROP 2 LAST $XR0 276 
J 0
(-3402 850);
DISPLAY 0.638298 (-3402 850);
PAINT MONO (-3402 850);
FORCEPROP 2 LAST CDS_LIB standard
J 0
(-3150 850);
DISPLAY INVISIBLE (-3150 850);
FORCEPROP 1 LAST OFFPAGE TRUE
J 0
(-2825 725);
DISPLAY 0.872340 (-2825 725);
PAINT AQUA (-2825 725);
DISPLAY INVISIBLE (-2825 725);
FORCEPROP 1 LAST COMMENT_BODY TRUE
J 0
(-3025 750);
DISPLAY 0.872340 (-3025 750);
PAINT GREEN (-3025 750);
DISPLAY INVISIBLE (-3025 750);
FORCEPROP 2 LAST PATH I22
J 0
(-3400 900);
DISPLAY 0.680851 (-3400 900);
DISPLAY INVISIBLE (-3400 900);
FORCEADD OFFPAGE..1
(-3150 900);
FORCEPROP 2 LAST $XR0 276 
J 0
(-3402 900);
DISPLAY 0.638298 (-3402 900);
PAINT MONO (-3402 900);
FORCEPROP 2 LAST CDS_LIB standard
J 0
(-3150 900);
DISPLAY INVISIBLE (-3150 900);
FORCEPROP 1 LAST OFFPAGE TRUE
J 0
(-2825 775);
DISPLAY 0.872340 (-2825 775);
PAINT AQUA (-2825 775);
DISPLAY INVISIBLE (-2825 775);
FORCEPROP 1 LAST COMMENT_BODY TRUE
J 0
(-3025 800);
DISPLAY 0.872340 (-3025 800);
PAINT GREEN (-3025 800);
DISPLAY INVISIBLE (-3025 800);
FORCEPROP 2 LAST PATH I23
J 0
(-3400 950);
DISPLAY 0.680851 (-3400 950);
DISPLAY INVISIBLE (-3400 950);
FORCEADD OFFPAGE..5
(-3150 1000);
FORCEPROP 2 LAST $XR0 286 
J 0
(-3405 1000);
DISPLAY 0.638298 (-3405 1000);
PAINT MONO (-3405 1000);
FORCEPROP 2 LAST CDS_LIB standard
J 0
(-3150 1000);
DISPLAY INVISIBLE (-3150 1000);
FORCEPROP 1 LAST OFFPAGE TRUE
J 0
(-2825 875);
DISPLAY 0.872340 (-2825 875);
PAINT AQUA (-2825 875);
DISPLAY INVISIBLE (-2825 875);
FORCEPROP 1 LAST COMMENT_BODY TRUE
J 0
(-3050 925);
DISPLAY 1.170213 (-3050 925);
PAINT GREEN (-3050 925);
DISPLAY INVISIBLE (-3050 925);
FORCEPROP 2 LAST PATH I24
J 0
(-3425 1050);
DISPLAY 0.680851 (-3425 1050);
DISPLAY INVISIBLE (-3425 1050);
FORCEADD OFFPAGE..2
R 2
(-3150 1050);
FORCEPROP 2 LAST $XR0 286 
J 0
(-3405 1050);
DISPLAY 0.638298 (-3405 1050);
PAINT MONO (-3405 1050);
FORCEPROP 2 LAST CDS_LIB standard
J 0
(-3150 1050);
DISPLAY INVISIBLE (-3150 1050);
FORCEPROP 1 LAST OFFPAGE TRUE
J 2
(-3475 925);
DISPLAY 0.872340 (-3475 925);
PAINT AQUA (-3475 925);
DISPLAY INVISIBLE (-3475 925);
FORCEPROP 1 LAST COMMENT_BODY TRUE
J 2
(-3105 955);
DISPLAY 0.872340 (-3105 955);
PAINT GREEN (-3105 955);
DISPLAY INVISIBLE (-3105 955);
FORCEPROP 2 LAST PATH I25
J 0
(-3425 1100);
DISPLAY 0.680851 (-3425 1100);
DISPLAY INVISIBLE (-3425 1100);
FORCEADD OFFPAGE..5
(-3150 1150);
FORCEPROP 2 LAST $XR0 275 
J 0
(-3405 1150);
DISPLAY 0.638298 (-3405 1150);
PAINT MONO (-3405 1150);
FORCEPROP 2 LAST CDS_LIB standard
J 0
(-3150 1150);
DISPLAY INVISIBLE (-3150 1150);
FORCEPROP 1 LAST OFFPAGE TRUE
J 0
(-2825 1025);
DISPLAY 0.872340 (-2825 1025);
PAINT AQUA (-2825 1025);
DISPLAY INVISIBLE (-2825 1025);
FORCEPROP 1 LAST COMMENT_BODY TRUE
J 0
(-3050 1075);
DISPLAY 1.170213 (-3050 1075);
PAINT GREEN (-3050 1075);
DISPLAY INVISIBLE (-3050 1075);
FORCEPROP 2 LAST PATH I26
J 0
(-3425 1200);
DISPLAY 0.680851 (-3425 1200);
DISPLAY INVISIBLE (-3425 1200);
FORCEADD OFFPAGE..2
R 2
(-3150 1200);
FORCEPROP 2 LAST $XR0 275 
J 0
(-3405 1200);
DISPLAY 0.638298 (-3405 1200);
PAINT MONO (-3405 1200);
FORCEPROP 2 LAST CDS_LIB standard
J 0
(-3150 1200);
DISPLAY INVISIBLE (-3150 1200);
FORCEPROP 1 LAST OFFPAGE TRUE
J 2
(-3475 1075);
DISPLAY 0.872340 (-3475 1075);
PAINT AQUA (-3475 1075);
DISPLAY INVISIBLE (-3475 1075);
FORCEPROP 1 LAST COMMENT_BODY TRUE
J 2
(-3105 1105);
DISPLAY 0.872340 (-3105 1105);
PAINT GREEN (-3105 1105);
DISPLAY INVISIBLE (-3105 1105);
FORCEPROP 2 LAST PATH I27
J 0
(-3425 1250);
DISPLAY 0.680851 (-3425 1250);
DISPLAY INVISIBLE (-3425 1250);
FORCEADD OFFPAGE..2
R 2
(-3150 1300);
FORCEPROP 2 LAST $XR0 126 
J 0
(-3405 1300);
DISPLAY 0.638298 (-3405 1300);
PAINT MONO (-3405 1300);
FORCEPROP 2 LAST CDS_LIB standard
J 0
(-3150 1300);
DISPLAY INVISIBLE (-3150 1300);
FORCEPROP 1 LAST OFFPAGE TRUE
J 2
(-3475 1175);
DISPLAY 0.872340 (-3475 1175);
PAINT AQUA (-3475 1175);
DISPLAY INVISIBLE (-3475 1175);
FORCEPROP 1 LAST COMMENT_BODY TRUE
J 2
(-3105 1205);
DISPLAY 0.872340 (-3105 1205);
PAINT GREEN (-3105 1205);
DISPLAY INVISIBLE (-3105 1205);
FORCEPROP 2 LAST PATH I28
J 0
(-3425 1350);
DISPLAY 0.680851 (-3425 1350);
DISPLAY INVISIBLE (-3425 1350);
FORCEADD OFFPAGE..1
(-3150 1550);
FORCEPROP 2 LAST $XR0 287 
J 0
(-3402 1550);
DISPLAY 0.638298 (-3402 1550);
PAINT MONO (-3402 1550);
FORCEPROP 2 LAST CDS_LIB standard
J 0
(-3150 1550);
DISPLAY INVISIBLE (-3150 1550);
FORCEPROP 1 LAST OFFPAGE TRUE
J 0
(-2825 1425);
DISPLAY 0.872340 (-2825 1425);
PAINT AQUA (-2825 1425);
DISPLAY INVISIBLE (-2825 1425);
FORCEPROP 1 LAST COMMENT_BODY TRUE
J 0
(-3025 1450);
DISPLAY 0.872340 (-3025 1450);
PAINT GREEN (-3025 1450);
DISPLAY INVISIBLE (-3025 1450);
FORCEPROP 2 LAST PATH I29
J 0
(-3400 1600);
DISPLAY 0.680851 (-3400 1600);
DISPLAY INVISIBLE (-3400 1600);
FORCEADD OFFPAGE..1
(-3150 -750);
FORCEPROP 2 LAST $XR0 276 
J 0
(-3402 -750);
DISPLAY 0.638298 (-3402 -750);
PAINT MONO (-3402 -750);
FORCEPROP 2 LAST CDS_LIB standard
J 0
(-3150 -750);
DISPLAY INVISIBLE (-3150 -750);
FORCEPROP 1 LAST OFFPAGE TRUE
J 0
(-2825 -875);
DISPLAY 0.872340 (-2825 -875);
PAINT AQUA (-2825 -875);
DISPLAY INVISIBLE (-2825 -875);
FORCEPROP 1 LAST COMMENT_BODY TRUE
J 0
(-3025 -850);
DISPLAY 0.872340 (-3025 -850);
PAINT GREEN (-3025 -850);
DISPLAY INVISIBLE (-3025 -850);
FORCEPROP 2 LAST PATH I3
J 0
(-3400 -700);
DISPLAY 0.680851 (-3400 -700);
DISPLAY INVISIBLE (-3400 -700);
FORCEADD OFFPAGE..1
(-3150 1600);
FORCEPROP 2 LAST $XR0 287 
J 0
(-3402 1600);
DISPLAY 0.638298 (-3402 1600);
PAINT MONO (-3402 1600);
FORCEPROP 2 LAST CDS_LIB standard
J 0
(-3150 1600);
DISPLAY INVISIBLE (-3150 1600);
FORCEPROP 1 LAST OFFPAGE TRUE
J 0
(-2825 1475);
DISPLAY 0.872340 (-2825 1475);
PAINT AQUA (-2825 1475);
DISPLAY INVISIBLE (-2825 1475);
FORCEPROP 1 LAST COMMENT_BODY TRUE
J 0
(-3025 1500);
DISPLAY 0.872340 (-3025 1500);
PAINT GREEN (-3025 1500);
DISPLAY INVISIBLE (-3025 1500);
FORCEPROP 2 LAST PATH I30
J 0
(-3400 1650);
DISPLAY 0.680851 (-3400 1650);
DISPLAY INVISIBLE (-3400 1650);
FORCEADD OFFPAGE..1
(-3150 1700);
FORCEPROP 2 LAST $XR0 276 
J 0
(-3402 1700);
DISPLAY 0.638298 (-3402 1700);
PAINT MONO (-3402 1700);
FORCEPROP 2 LAST CDS_LIB standard
J 0
(-3150 1700);
DISPLAY INVISIBLE (-3150 1700);
FORCEPROP 1 LAST OFFPAGE TRUE
J 0
(-2825 1575);
DISPLAY 0.872340 (-2825 1575);
PAINT AQUA (-2825 1575);
DISPLAY INVISIBLE (-2825 1575);
FORCEPROP 1 LAST COMMENT_BODY TRUE
J 0
(-3025 1600);
DISPLAY 0.872340 (-3025 1600);
PAINT GREEN (-3025 1600);
DISPLAY INVISIBLE (-3025 1600);
FORCEPROP 2 LAST PATH I31
J 0
(-3425 1750);
DISPLAY 0.680851 (-3425 1750);
DISPLAY INVISIBLE (-3425 1750);
FORCEADD OFFPAGE..1
(-3150 1750);
FORCEPROP 2 LAST $XR0 276 
J 0
(-3402 1750);
DISPLAY 0.638298 (-3402 1750);
PAINT MONO (-3402 1750);
FORCEPROP 2 LAST CDS_LIB standard
J 0
(-3150 1750);
DISPLAY INVISIBLE (-3150 1750);
FORCEPROP 1 LAST OFFPAGE TRUE
J 0
(-2825 1625);
DISPLAY 0.872340 (-2825 1625);
PAINT AQUA (-2825 1625);
DISPLAY INVISIBLE (-2825 1625);
FORCEPROP 1 LAST COMMENT_BODY TRUE
J 0
(-3025 1650);
DISPLAY 0.872340 (-3025 1650);
PAINT GREEN (-3025 1650);
DISPLAY INVISIBLE (-3025 1650);
FORCEPROP 2 LAST PATH I32
J 0
(-3425 1800);
DISPLAY 0.680851 (-3425 1800);
DISPLAY INVISIBLE (-3425 1800);
FORCEADD OFFPAGE..5
(-3150 1850);
FORCEPROP 2 LAST $XR0 286 
J 0
(-3405 1850);
DISPLAY 0.638298 (-3405 1850);
PAINT MONO (-3405 1850);
FORCEPROP 2 LAST CDS_LIB standard
J 0
(-3150 1850);
DISPLAY INVISIBLE (-3150 1850);
FORCEPROP 1 LAST OFFPAGE TRUE
J 0
(-2825 1725);
DISPLAY 0.872340 (-2825 1725);
PAINT AQUA (-2825 1725);
DISPLAY INVISIBLE (-2825 1725);
FORCEPROP 1 LAST COMMENT_BODY TRUE
J 0
(-3050 1775);
DISPLAY 1.170213 (-3050 1775);
PAINT GREEN (-3050 1775);
DISPLAY INVISIBLE (-3050 1775);
FORCEPROP 2 LAST PATH I33
J 0
(-3425 1900);
DISPLAY 0.680851 (-3425 1900);
DISPLAY INVISIBLE (-3425 1900);
FORCEADD OFFPAGE..2
R 2
(-3150 1900);
FORCEPROP 2 LAST $XR0 286 
J 0
(-3405 1900);
DISPLAY 0.638298 (-3405 1900);
PAINT MONO (-3405 1900);
FORCEPROP 2 LAST CDS_LIB standard
J 0
(-3150 1900);
DISPLAY INVISIBLE (-3150 1900);
FORCEPROP 1 LAST OFFPAGE TRUE
J 2
(-3475 1775);
DISPLAY 0.872340 (-3475 1775);
PAINT AQUA (-3475 1775);
DISPLAY INVISIBLE (-3475 1775);
FORCEPROP 1 LAST COMMENT_BODY TRUE
J 2
(-3105 1805);
DISPLAY 0.872340 (-3105 1805);
PAINT GREEN (-3105 1805);
DISPLAY INVISIBLE (-3105 1805);
FORCEPROP 2 LAST PATH I34
J 0
(-3425 1950);
DISPLAY 0.680851 (-3425 1950);
DISPLAY INVISIBLE (-3425 1950);
FORCEADD OFFPAGE..2
R 2
(-3150 2050);
FORCEPROP 2 LAST $XR0 275 
J 0
(-3405 2050);
DISPLAY 0.638298 (-3405 2050);
PAINT MONO (-3405 2050);
FORCEPROP 2 LAST CDS_LIB standard
J 0
(-3150 2050);
DISPLAY INVISIBLE (-3150 2050);
FORCEPROP 1 LAST OFFPAGE TRUE
J 2
(-3475 1925);
DISPLAY 0.872340 (-3475 1925);
PAINT AQUA (-3475 1925);
DISPLAY INVISIBLE (-3475 1925);
FORCEPROP 1 LAST COMMENT_BODY TRUE
J 2
(-3105 1955);
DISPLAY 0.872340 (-3105 1955);
PAINT GREEN (-3105 1955);
DISPLAY INVISIBLE (-3105 1955);
FORCEPROP 2 LAST PATH I35
J 0
(-3425 2100);
DISPLAY 0.680851 (-3425 2100);
DISPLAY INVISIBLE (-3425 2100);
FORCEADD OFFPAGE..5
(-3150 2000);
FORCEPROP 2 LAST $XR0 275 
J 0
(-3405 2000);
DISPLAY 0.638298 (-3405 2000);
PAINT MONO (-3405 2000);
FORCEPROP 2 LAST CDS_LIB standard
J 0
(-3150 2000);
DISPLAY INVISIBLE (-3150 2000);
FORCEPROP 1 LAST OFFPAGE TRUE
J 0
(-2825 1875);
DISPLAY 0.872340 (-2825 1875);
PAINT AQUA (-2825 1875);
DISPLAY INVISIBLE (-2825 1875);
FORCEPROP 1 LAST COMMENT_BODY TRUE
J 0
(-3050 1925);
DISPLAY 1.170213 (-3050 1925);
PAINT GREEN (-3050 1925);
DISPLAY INVISIBLE (-3050 1925);
FORCEPROP 2 LAST PATH I36
J 0
(-3425 2050);
DISPLAY 0.680851 (-3425 2050);
DISPLAY INVISIBLE (-3425 2050);
FORCEADD OFFPAGE..1
(1375 -950);
FORCEPROP 2 LAST $XR0 287 
J 0
(1123 -950);
DISPLAY 0.638298 (1123 -950);
PAINT MONO (1123 -950);
FORCEPROP 2 LAST CDS_LIB standard
J 0
(1375 -950);
DISPLAY INVISIBLE (1375 -950);
FORCEPROP 1 LAST OFFPAGE TRUE
J 0
(1700 -1075);
DISPLAY 0.872340 (1700 -1075);
PAINT AQUA (1700 -1075);
DISPLAY INVISIBLE (1700 -1075);
FORCEPROP 1 LAST COMMENT_BODY TRUE
J 0
(1500 -1050);
DISPLAY 0.872340 (1500 -1050);
PAINT GREEN (1500 -1050);
DISPLAY INVISIBLE (1500 -1050);
FORCEPROP 2 LAST PATH I37
J 0
(1125 -900);
DISPLAY 0.680851 (1125 -900);
DISPLAY INVISIBLE (1125 -900);
FORCEADD OFFPAGE..1
(1375 -900);
FORCEPROP 2 LAST $XR0 287 
J 0
(1123 -900);
DISPLAY 0.638298 (1123 -900);
PAINT MONO (1123 -900);
FORCEPROP 2 LAST CDS_LIB standard
J 0
(1375 -900);
DISPLAY INVISIBLE (1375 -900);
FORCEPROP 1 LAST OFFPAGE TRUE
J 0
(1700 -1025);
DISPLAY 0.872340 (1700 -1025);
PAINT AQUA (1700 -1025);
DISPLAY INVISIBLE (1700 -1025);
FORCEPROP 1 LAST COMMENT_BODY TRUE
J 0
(1500 -1000);
DISPLAY 0.872340 (1500 -1000);
PAINT GREEN (1500 -1000);
DISPLAY INVISIBLE (1500 -1000);
FORCEPROP 2 LAST PATH I38
J 0
(1125 -850);
DISPLAY 0.680851 (1125 -850);
DISPLAY INVISIBLE (1125 -850);
FORCEADD OFFPAGE..1
(1375 -800);
FORCEPROP 2 LAST $XR0 276 
J 0
(1123 -800);
DISPLAY 0.638298 (1123 -800);
PAINT MONO (1123 -800);
FORCEPROP 2 LAST CDS_LIB standard
J 0
(1375 -800);
DISPLAY INVISIBLE (1375 -800);
FORCEPROP 1 LAST OFFPAGE TRUE
J 0
(1700 -925);
DISPLAY 0.872340 (1700 -925);
PAINT AQUA (1700 -925);
DISPLAY INVISIBLE (1700 -925);
FORCEPROP 1 LAST COMMENT_BODY TRUE
J 0
(1500 -900);
DISPLAY 0.872340 (1500 -900);
PAINT GREEN (1500 -900);
DISPLAY INVISIBLE (1500 -900);
FORCEPROP 2 LAST PATH I39
J 0
(1125 -750);
DISPLAY 0.680851 (1125 -750);
DISPLAY INVISIBLE (1125 -750);
FORCEADD OFFPAGE..1
(-3150 -700);
FORCEPROP 2 LAST $XR0 276 
J 0
(-3402 -700);
DISPLAY 0.638298 (-3402 -700);
PAINT MONO (-3402 -700);
FORCEPROP 2 LAST CDS_LIB standard
J 0
(-3150 -700);
DISPLAY INVISIBLE (-3150 -700);
FORCEPROP 1 LAST OFFPAGE TRUE
J 0
(-2825 -825);
DISPLAY 0.872340 (-2825 -825);
PAINT AQUA (-2825 -825);
DISPLAY INVISIBLE (-2825 -825);
FORCEPROP 1 LAST COMMENT_BODY TRUE
J 0
(-3025 -800);
DISPLAY 0.872340 (-3025 -800);
PAINT GREEN (-3025 -800);
DISPLAY INVISIBLE (-3025 -800);
FORCEPROP 2 LAST PATH I4
J 0
(-3400 -650);
DISPLAY 0.680851 (-3400 -650);
DISPLAY INVISIBLE (-3400 -650);
FORCEADD OFFPAGE..1
(1375 -750);
FORCEPROP 2 LAST $XR0 276 
J 0
(1123 -750);
DISPLAY 0.638298 (1123 -750);
PAINT MONO (1123 -750);
FORCEPROP 2 LAST CDS_LIB standard
J 0
(1375 -750);
DISPLAY INVISIBLE (1375 -750);
FORCEPROP 1 LAST OFFPAGE TRUE
J 0
(1700 -875);
DISPLAY 0.872340 (1700 -875);
PAINT AQUA (1700 -875);
DISPLAY INVISIBLE (1700 -875);
FORCEPROP 1 LAST COMMENT_BODY TRUE
J 0
(1500 -850);
DISPLAY 0.872340 (1500 -850);
PAINT GREEN (1500 -850);
DISPLAY INVISIBLE (1500 -850);
FORCEPROP 2 LAST PATH I40
J 0
(1125 -700);
DISPLAY 0.680851 (1125 -700);
DISPLAY INVISIBLE (1125 -700);
FORCEADD OFFPAGE..2
R 2
(1375 -600);
FORCEPROP 2 LAST $XR0 286 
J 0
(1090 -600);
DISPLAY 0.638298 (1090 -600);
PAINT MONO (1090 -600);
FORCEPROP 2 LAST CDS_LIB standard
J 0
(1375 -600);
DISPLAY INVISIBLE (1375 -600);
FORCEPROP 1 LAST OFFPAGE TRUE
J 2
(1050 -725);
DISPLAY 0.872340 (1050 -725);
PAINT AQUA (1050 -725);
DISPLAY INVISIBLE (1050 -725);
FORCEPROP 1 LAST COMMENT_BODY TRUE
J 2
(1420 -695);
DISPLAY 0.872340 (1420 -695);
PAINT GREEN (1420 -695);
DISPLAY INVISIBLE (1420 -695);
FORCEPROP 2 LAST PATH I41
J 0
(1100 -550);
DISPLAY 0.680851 (1100 -550);
DISPLAY INVISIBLE (1100 -550);
FORCEADD OFFPAGE..5
(1375 -650);
FORCEPROP 2 LAST $XR0 286 
J 0
(1090 -650);
DISPLAY 0.638298 (1090 -650);
PAINT MONO (1090 -650);
FORCEPROP 2 LAST CDS_LIB standard
J 0
(1375 -650);
DISPLAY INVISIBLE (1375 -650);
FORCEPROP 1 LAST OFFPAGE TRUE
J 0
(1700 -775);
DISPLAY 0.872340 (1700 -775);
PAINT AQUA (1700 -775);
DISPLAY INVISIBLE (1700 -775);
FORCEPROP 1 LAST COMMENT_BODY TRUE
J 0
(1475 -725);
DISPLAY 1.170213 (1475 -725);
PAINT GREEN (1475 -725);
DISPLAY INVISIBLE (1475 -725);
FORCEPROP 2 LAST PATH I42
J 0
(1100 -600);
DISPLAY 0.680851 (1100 -600);
DISPLAY INVISIBLE (1100 -600);
FORCEADD OFFPAGE..5
(1375 -500);
FORCEPROP 2 LAST $XR0 275 
J 0
(1090 -500);
DISPLAY 0.638298 (1090 -500);
PAINT MONO (1090 -500);
FORCEPROP 2 LAST CDS_LIB standard
J 0
(1375 -500);
DISPLAY INVISIBLE (1375 -500);
FORCEPROP 1 LAST OFFPAGE TRUE
J 0
(1700 -625);
DISPLAY 0.872340 (1700 -625);
PAINT AQUA (1700 -625);
DISPLAY INVISIBLE (1700 -625);
FORCEPROP 1 LAST COMMENT_BODY TRUE
J 0
(1475 -575);
DISPLAY 1.170213 (1475 -575);
PAINT GREEN (1475 -575);
DISPLAY INVISIBLE (1475 -575);
FORCEPROP 2 LAST PATH I43
J 0
(1100 -450);
DISPLAY 0.680851 (1100 -450);
DISPLAY INVISIBLE (1100 -450);
FORCEADD OFFPAGE..2
R 2
(1375 -450);
FORCEPROP 2 LAST $XR0 275 
J 0
(1090 -450);
DISPLAY 0.638298 (1090 -450);
PAINT MONO (1090 -450);
FORCEPROP 2 LAST CDS_LIB standard
J 0
(1375 -450);
DISPLAY INVISIBLE (1375 -450);
FORCEPROP 1 LAST OFFPAGE TRUE
J 2
(1050 -575);
DISPLAY 0.872340 (1050 -575);
PAINT AQUA (1050 -575);
DISPLAY INVISIBLE (1050 -575);
FORCEPROP 1 LAST COMMENT_BODY TRUE
J 2
(1420 -545);
DISPLAY 0.872340 (1420 -545);
PAINT GREEN (1420 -545);
DISPLAY INVISIBLE (1420 -545);
FORCEPROP 2 LAST PATH I44
J 0
(1100 -400);
DISPLAY 0.680851 (1100 -400);
DISPLAY INVISIBLE (1100 -400);
FORCEADD OFFPAGE..2
R 2
(1400 -350);
FORCEPROP 2 LAST $XR0 125 
J 0
(1145 -350);
DISPLAY 0.638298 (1145 -350);
PAINT MONO (1145 -350);
FORCEPROP 2 LAST CDS_LIB standard
J 0
(1400 -350);
DISPLAY INVISIBLE (1400 -350);
FORCEPROP 1 LAST OFFPAGE TRUE
J 2
(1075 -475);
DISPLAY 0.872340 (1075 -475);
PAINT AQUA (1075 -475);
DISPLAY INVISIBLE (1075 -475);
FORCEPROP 1 LAST COMMENT_BODY TRUE
J 2
(1445 -445);
DISPLAY 0.872340 (1445 -445);
PAINT GREEN (1445 -445);
DISPLAY INVISIBLE (1445 -445);
FORCEPROP 2 LAST PATH I45
J 0
(1150 -300);
DISPLAY 0.680851 (1150 -300);
DISPLAY INVISIBLE (1150 -300);
FORCEADD OFFPAGE..1
(1375 -100);
FORCEPROP 2 LAST $XR0 287 
J 0
(1123 -100);
DISPLAY 0.638298 (1123 -100);
PAINT MONO (1123 -100);
FORCEPROP 2 LAST CDS_LIB standard
J 0
(1375 -100);
DISPLAY INVISIBLE (1375 -100);
FORCEPROP 1 LAST OFFPAGE TRUE
J 0
(1700 -225);
DISPLAY 0.872340 (1700 -225);
PAINT AQUA (1700 -225);
DISPLAY INVISIBLE (1700 -225);
FORCEPROP 1 LAST COMMENT_BODY TRUE
J 0
(1500 -200);
DISPLAY 0.872340 (1500 -200);
PAINT GREEN (1500 -200);
DISPLAY INVISIBLE (1500 -200);
FORCEPROP 2 LAST PATH I46
J 0
(1125 -50);
DISPLAY 0.680851 (1125 -50);
DISPLAY INVISIBLE (1125 -50);
FORCEADD OFFPAGE..1
(1375 -50);
FORCEPROP 2 LAST $XR0 287 
J 0
(1123 -50);
DISPLAY 0.638298 (1123 -50);
PAINT MONO (1123 -50);
FORCEPROP 2 LAST CDS_LIB standard
J 0
(1375 -50);
DISPLAY INVISIBLE (1375 -50);
FORCEPROP 1 LAST OFFPAGE TRUE
J 0
(1700 -175);
DISPLAY 0.872340 (1700 -175);
PAINT AQUA (1700 -175);
DISPLAY INVISIBLE (1700 -175);
FORCEPROP 1 LAST COMMENT_BODY TRUE
J 0
(1500 -150);
DISPLAY 0.872340 (1500 -150);
PAINT GREEN (1500 -150);
DISPLAY INVISIBLE (1500 -150);
FORCEPROP 2 LAST PATH I47
J 0
(1125 0);
DISPLAY 0.680851 (1125 0);
DISPLAY INVISIBLE (1125 0);
FORCEADD OFFPAGE..1
(1375 100);
FORCEPROP 2 LAST $XR0 276 
J 0
(1123 100);
DISPLAY 0.638298 (1123 100);
PAINT MONO (1123 100);
FORCEPROP 2 LAST CDS_LIB standard
J 0
(1375 100);
DISPLAY INVISIBLE (1375 100);
FORCEPROP 1 LAST OFFPAGE TRUE
J 0
(1700 -25);
DISPLAY 0.872340 (1700 -25);
PAINT AQUA (1700 -25);
DISPLAY INVISIBLE (1700 -25);
FORCEPROP 1 LAST COMMENT_BODY TRUE
J 0
(1500 0);
DISPLAY 0.872340 (1500 0);
PAINT GREEN (1500 0);
DISPLAY INVISIBLE (1500 0);
FORCEPROP 2 LAST PATH I48
J 0
(1125 150);
DISPLAY 0.680851 (1125 150);
DISPLAY INVISIBLE (1125 150);
FORCEADD OFFPAGE..1
(1375 50);
FORCEPROP 2 LAST $XR0 276 
J 0
(1123 50);
DISPLAY 0.638298 (1123 50);
PAINT MONO (1123 50);
FORCEPROP 2 LAST CDS_LIB standard
J 0
(1375 50);
DISPLAY INVISIBLE (1375 50);
FORCEPROP 1 LAST OFFPAGE TRUE
J 0
(1700 -75);
DISPLAY 0.872340 (1700 -75);
PAINT AQUA (1700 -75);
DISPLAY INVISIBLE (1700 -75);
FORCEPROP 1 LAST COMMENT_BODY TRUE
J 0
(1500 -50);
DISPLAY 0.872340 (1500 -50);
PAINT GREEN (1500 -50);
DISPLAY INVISIBLE (1500 -50);
FORCEPROP 2 LAST PATH I49
J 0
(1125 100);
DISPLAY 0.680851 (1125 100);
DISPLAY INVISIBLE (1125 100);
FORCEADD OFFPAGE..5
(-3150 -600);
FORCEPROP 2 LAST $XR0 286 
J 0
(-3405 -600);
DISPLAY 0.638298 (-3405 -600);
PAINT MONO (-3405 -600);
FORCEPROP 2 LAST CDS_LIB standard
J 0
(-3150 -600);
DISPLAY INVISIBLE (-3150 -600);
FORCEPROP 1 LAST OFFPAGE TRUE
J 0
(-2825 -725);
DISPLAY 0.872340 (-2825 -725);
PAINT AQUA (-2825 -725);
DISPLAY INVISIBLE (-2825 -725);
FORCEPROP 1 LAST COMMENT_BODY TRUE
J 0
(-3050 -675);
DISPLAY 1.170213 (-3050 -675);
PAINT GREEN (-3050 -675);
DISPLAY INVISIBLE (-3050 -675);
FORCEPROP 2 LAST PATH I5
J 0
(-3425 -550);
DISPLAY 0.680851 (-3425 -550);
DISPLAY INVISIBLE (-3425 -550);
FORCEADD OFFPAGE..5
(1375 200);
FORCEPROP 2 LAST $XR0 286 
J 0
(1090 200);
DISPLAY 0.638298 (1090 200);
PAINT MONO (1090 200);
FORCEPROP 2 LAST CDS_LIB standard
J 0
(1375 200);
DISPLAY INVISIBLE (1375 200);
FORCEPROP 1 LAST OFFPAGE TRUE
J 0
(1700 75);
DISPLAY 0.872340 (1700 75);
PAINT AQUA (1700 75);
DISPLAY INVISIBLE (1700 75);
FORCEPROP 1 LAST COMMENT_BODY TRUE
J 0
(1475 125);
DISPLAY 1.170213 (1475 125);
PAINT GREEN (1475 125);
DISPLAY INVISIBLE (1475 125);
FORCEPROP 2 LAST PATH I50
J 0
(1100 250);
DISPLAY 0.680851 (1100 250);
DISPLAY INVISIBLE (1100 250);
FORCEADD UNIVERSAL_GND..1
(2450 -1400);
FORCEPROP 3 LASTPIN (2450 -1350) SIG_NAME GND\g
J 0
(2460 -1340);
DISPLAY 0.659574 (2460 -1340);
PAINT MONO (2460 -1340);
DISPLAY INVISIBLE (2460 -1340);
FORCEPROP 2 LAST CDS_LIB pure_quanta_power
J 0
(2450 -1400);
DISPLAY INVISIBLE (2450 -1400);
FORCEPROP 1 LAST HDL_POWER GND
J 1
(2475 -1475);
DISPLAY 0.872340 (2475 -1475);
PAINT GREEN (2475 -1475);
DISPLAY INVISIBLE (2475 -1475);
FORCEPROP 1 LAST PATH I51
J 0
(2525 -1400);
DISPLAY 0.872340 (2525 -1400);
PAINT AQUA (2525 -1400);
DISPLAY INVISIBLE (2525 -1400);
FORCEADD OFFPAGE..2
R 2
(1375 250);
FORCEPROP 2 LAST $XR0 286 
J 0
(1090 250);
DISPLAY 0.638298 (1090 250);
PAINT MONO (1090 250);
FORCEPROP 2 LAST CDS_LIB standard
J 0
(1375 250);
DISPLAY INVISIBLE (1375 250);
FORCEPROP 1 LAST OFFPAGE TRUE
J 2
(1050 125);
DISPLAY 0.872340 (1050 125);
PAINT AQUA (1050 125);
DISPLAY INVISIBLE (1050 125);
FORCEPROP 1 LAST COMMENT_BODY TRUE
J 2
(1420 155);
DISPLAY 0.872340 (1420 155);
PAINT GREEN (1420 155);
DISPLAY INVISIBLE (1420 155);
FORCEPROP 2 LAST PATH I52
J 0
(1100 300);
DISPLAY 0.680851 (1100 300);
DISPLAY INVISIBLE (1100 300);
FORCEADD OFFPAGE..2
R 2
(1375 400);
FORCEPROP 2 LAST $XR0 275 
J 0
(1090 400);
DISPLAY 0.638298 (1090 400);
PAINT MONO (1090 400);
FORCEPROP 2 LAST CDS_LIB standard
J 0
(1375 400);
DISPLAY INVISIBLE (1375 400);
FORCEPROP 1 LAST OFFPAGE TRUE
J 2
(1050 275);
DISPLAY 0.872340 (1050 275);
PAINT AQUA (1050 275);
DISPLAY INVISIBLE (1050 275);
FORCEPROP 1 LAST COMMENT_BODY TRUE
J 2
(1420 305);
DISPLAY 0.872340 (1420 305);
PAINT GREEN (1420 305);
DISPLAY INVISIBLE (1420 305);
FORCEPROP 2 LAST PATH I53
J 0
(1100 450);
DISPLAY 0.680851 (1100 450);
DISPLAY INVISIBLE (1100 450);
FORCEADD OFFPAGE..5
(1375 350);
FORCEPROP 2 LAST $XR0 275 
J 0
(1090 350);
DISPLAY 0.638298 (1090 350);
PAINT MONO (1090 350);
FORCEPROP 2 LAST CDS_LIB standard
J 0
(1375 350);
DISPLAY INVISIBLE (1375 350);
FORCEPROP 1 LAST OFFPAGE TRUE
J 0
(1700 225);
DISPLAY 0.872340 (1700 225);
PAINT AQUA (1700 225);
DISPLAY INVISIBLE (1700 225);
FORCEPROP 1 LAST COMMENT_BODY TRUE
J 0
(1475 275);
DISPLAY 1.170213 (1475 275);
PAINT GREEN (1475 275);
DISPLAY INVISIBLE (1475 275);
FORCEPROP 2 LAST PATH I54
J 0
(1100 400);
DISPLAY 0.680851 (1100 400);
DISPLAY INVISIBLE (1100 400);
FORCEADD OFFPAGE..1
(1375 650);
FORCEPROP 2 LAST $XR0 287 
J 0
(1123 650);
DISPLAY 0.638298 (1123 650);
PAINT MONO (1123 650);
FORCEPROP 2 LAST CDS_LIB standard
J 0
(1375 650);
DISPLAY INVISIBLE (1375 650);
FORCEPROP 1 LAST OFFPAGE TRUE
J 0
(1700 525);
DISPLAY 0.872340 (1700 525);
PAINT AQUA (1700 525);
DISPLAY INVISIBLE (1700 525);
FORCEPROP 1 LAST COMMENT_BODY TRUE
J 0
(1500 550);
DISPLAY 0.872340 (1500 550);
PAINT GREEN (1500 550);
DISPLAY INVISIBLE (1500 550);
FORCEPROP 2 LAST PATH I55
J 0
(1125 700);
DISPLAY 0.680851 (1125 700);
DISPLAY INVISIBLE (1125 700);
FORCEADD OFFPAGE..1
(1375 700);
FORCEPROP 2 LAST $XR0 287 
J 0
(1123 700);
DISPLAY 0.638298 (1123 700);
PAINT MONO (1123 700);
FORCEPROP 2 LAST CDS_LIB standard
J 0
(1375 700);
DISPLAY INVISIBLE (1375 700);
FORCEPROP 1 LAST OFFPAGE TRUE
J 0
(1700 575);
DISPLAY 0.872340 (1700 575);
PAINT AQUA (1700 575);
DISPLAY INVISIBLE (1700 575);
FORCEPROP 1 LAST COMMENT_BODY TRUE
J 0
(1500 600);
DISPLAY 0.872340 (1500 600);
PAINT GREEN (1500 600);
DISPLAY INVISIBLE (1500 600);
FORCEPROP 2 LAST PATH I56
J 0
(1125 750);
DISPLAY 0.680851 (1125 750);
DISPLAY INVISIBLE (1125 750);
FORCEADD OFFPAGE..1
(1375 850);
FORCEPROP 2 LAST $XR0 276 
J 0
(1123 850);
DISPLAY 0.638298 (1123 850);
PAINT MONO (1123 850);
FORCEPROP 2 LAST CDS_LIB standard
J 0
(1375 850);
DISPLAY INVISIBLE (1375 850);
FORCEPROP 1 LAST OFFPAGE TRUE
J 0
(1700 725);
DISPLAY 0.872340 (1700 725);
PAINT AQUA (1700 725);
DISPLAY INVISIBLE (1700 725);
FORCEPROP 1 LAST COMMENT_BODY TRUE
J 0
(1500 750);
DISPLAY 0.872340 (1500 750);
PAINT GREEN (1500 750);
DISPLAY INVISIBLE (1500 750);
FORCEPROP 2 LAST PATH I57
J 0
(1125 900);
DISPLAY 0.680851 (1125 900);
DISPLAY INVISIBLE (1125 900);
FORCEADD OFFPAGE..1
(1375 800);
FORCEPROP 2 LAST $XR0 276 
J 0
(1123 800);
DISPLAY 0.638298 (1123 800);
PAINT MONO (1123 800);
FORCEPROP 2 LAST CDS_LIB standard
J 0
(1375 800);
DISPLAY INVISIBLE (1375 800);
FORCEPROP 1 LAST OFFPAGE TRUE
J 0
(1700 675);
DISPLAY 0.872340 (1700 675);
PAINT AQUA (1700 675);
DISPLAY INVISIBLE (1700 675);
FORCEPROP 1 LAST COMMENT_BODY TRUE
J 0
(1500 700);
DISPLAY 0.872340 (1500 700);
PAINT GREEN (1500 700);
DISPLAY INVISIBLE (1500 700);
FORCEPROP 2 LAST PATH I58
J 0
(1125 850);
DISPLAY 0.680851 (1125 850);
DISPLAY INVISIBLE (1125 850);
FORCEADD OFFPAGE..5
(1375 950);
FORCEPROP 2 LAST $XR0 286 
J 0
(1090 950);
DISPLAY 0.638298 (1090 950);
PAINT MONO (1090 950);
FORCEPROP 2 LAST CDS_LIB standard
J 0
(1375 950);
DISPLAY INVISIBLE (1375 950);
FORCEPROP 1 LAST OFFPAGE TRUE
J 0
(1700 825);
DISPLAY 0.872340 (1700 825);
PAINT AQUA (1700 825);
DISPLAY INVISIBLE (1700 825);
FORCEPROP 1 LAST COMMENT_BODY TRUE
J 0
(1475 875);
DISPLAY 1.170213 (1475 875);
PAINT GREEN (1475 875);
DISPLAY INVISIBLE (1475 875);
FORCEPROP 2 LAST PATH I59
J 0
(1100 1000);
DISPLAY 0.680851 (1100 1000);
DISPLAY INVISIBLE (1100 1000);
FORCEADD OFFPAGE..2
R 2
(-3150 -550);
FORCEPROP 2 LAST $XR0 286 
J 0
(-3405 -550);
DISPLAY 0.638298 (-3405 -550);
PAINT MONO (-3405 -550);
FORCEPROP 2 LAST CDS_LIB standard
J 0
(-3150 -550);
DISPLAY INVISIBLE (-3150 -550);
FORCEPROP 1 LAST OFFPAGE TRUE
J 2
(-3475 -675);
DISPLAY 0.872340 (-3475 -675);
PAINT AQUA (-3475 -675);
DISPLAY INVISIBLE (-3475 -675);
FORCEPROP 1 LAST COMMENT_BODY TRUE
J 2
(-3105 -645);
DISPLAY 0.872340 (-3105 -645);
PAINT GREEN (-3105 -645);
DISPLAY INVISIBLE (-3105 -645);
FORCEPROP 2 LAST PATH I6
J 0
(-3425 -500);
DISPLAY 0.680851 (-3425 -500);
DISPLAY INVISIBLE (-3425 -500);
FORCEADD OFFPAGE..2
R 2
(1375 1000);
FORCEPROP 2 LAST $XR0 286 
J 0
(1090 1000);
DISPLAY 0.638298 (1090 1000);
PAINT MONO (1090 1000);
FORCEPROP 2 LAST CDS_LIB standard
J 0
(1375 1000);
DISPLAY INVISIBLE (1375 1000);
FORCEPROP 1 LAST OFFPAGE TRUE
J 2
(1050 875);
DISPLAY 0.872340 (1050 875);
PAINT AQUA (1050 875);
DISPLAY INVISIBLE (1050 875);
FORCEPROP 1 LAST COMMENT_BODY TRUE
J 2
(1420 905);
DISPLAY 0.872340 (1420 905);
PAINT GREEN (1420 905);
DISPLAY INVISIBLE (1420 905);
FORCEPROP 2 LAST PATH I60
J 0
(1100 1050);
DISPLAY 0.680851 (1100 1050);
DISPLAY INVISIBLE (1100 1050);
FORCEADD OFFPAGE..5
(1375 1100);
FORCEPROP 2 LAST $XR0 275 
J 0
(1090 1100);
DISPLAY 0.638298 (1090 1100);
PAINT MONO (1090 1100);
FORCEPROP 2 LAST CDS_LIB standard
J 0
(1375 1100);
DISPLAY INVISIBLE (1375 1100);
FORCEPROP 1 LAST OFFPAGE TRUE
J 0
(1700 975);
DISPLAY 0.872340 (1700 975);
PAINT AQUA (1700 975);
DISPLAY INVISIBLE (1700 975);
FORCEPROP 1 LAST COMMENT_BODY TRUE
J 0
(1475 1025);
DISPLAY 1.170213 (1475 1025);
PAINT GREEN (1475 1025);
DISPLAY INVISIBLE (1475 1025);
FORCEPROP 2 LAST PATH I61
J 0
(1100 1150);
DISPLAY 0.680851 (1100 1150);
DISPLAY INVISIBLE (1100 1150);
FORCEADD OFFPAGE..2
R 2
(1375 1150);
FORCEPROP 2 LAST $XR0 275 
J 0
(1090 1150);
DISPLAY 0.638298 (1090 1150);
PAINT MONO (1090 1150);
FORCEPROP 2 LAST CDS_LIB standard
J 0
(1375 1150);
DISPLAY INVISIBLE (1375 1150);
FORCEPROP 1 LAST OFFPAGE TRUE
J 2
(1050 1025);
DISPLAY 0.872340 (1050 1025);
PAINT AQUA (1050 1025);
DISPLAY INVISIBLE (1050 1025);
FORCEPROP 1 LAST COMMENT_BODY TRUE
J 2
(1420 1055);
DISPLAY 0.872340 (1420 1055);
PAINT GREEN (1420 1055);
DISPLAY INVISIBLE (1420 1055);
FORCEPROP 2 LAST PATH I62
J 0
(1100 1200);
DISPLAY 0.680851 (1100 1200);
DISPLAY INVISIBLE (1100 1200);
FORCEADD OFFPAGE..2
R 2
(1400 1250);
FORCEPROP 2 LAST $XR0 125 
J 0
(1145 1250);
DISPLAY 0.638298 (1145 1250);
PAINT MONO (1145 1250);
FORCEPROP 2 LAST CDS_LIB standard
J 0
(1400 1250);
DISPLAY INVISIBLE (1400 1250);
FORCEPROP 1 LAST OFFPAGE TRUE
J 2
(1075 1125);
DISPLAY 0.872340 (1075 1125);
PAINT AQUA (1075 1125);
DISPLAY INVISIBLE (1075 1125);
FORCEPROP 1 LAST COMMENT_BODY TRUE
J 2
(1445 1155);
DISPLAY 0.872340 (1445 1155);
PAINT GREEN (1445 1155);
DISPLAY INVISIBLE (1445 1155);
FORCEPROP 2 LAST PATH I63
J 0
(1150 1300);
DISPLAY 0.680851 (1150 1300);
DISPLAY INVISIBLE (1150 1300);
FORCEADD OFFPAGE..1
(1375 1650);
FORCEPROP 2 LAST $XR0 276 
J 0
(1123 1650);
DISPLAY 0.638298 (1123 1650);
PAINT MONO (1123 1650);
FORCEPROP 2 LAST CDS_LIB standard
J 0
(1375 1650);
DISPLAY INVISIBLE (1375 1650);
FORCEPROP 1 LAST OFFPAGE TRUE
J 0
(1700 1525);
DISPLAY 0.872340 (1700 1525);
PAINT AQUA (1700 1525);
DISPLAY INVISIBLE (1700 1525);
FORCEPROP 1 LAST COMMENT_BODY TRUE
J 0
(1500 1550);
DISPLAY 0.872340 (1500 1550);
PAINT GREEN (1500 1550);
DISPLAY INVISIBLE (1500 1550);
FORCEPROP 2 LAST PATH I64
J 0
(1125 1700);
DISPLAY 0.680851 (1125 1700);
DISPLAY INVISIBLE (1125 1700);
FORCEADD OFFPAGE..1
(1375 1550);
FORCEPROP 2 LAST $XR0 287 
J 0
(1123 1550);
DISPLAY 0.638298 (1123 1550);
PAINT MONO (1123 1550);
FORCEPROP 2 LAST CDS_LIB standard
J 0
(1375 1550);
DISPLAY INVISIBLE (1375 1550);
FORCEPROP 1 LAST OFFPAGE TRUE
J 0
(1700 1425);
DISPLAY 0.872340 (1700 1425);
PAINT AQUA (1700 1425);
DISPLAY INVISIBLE (1700 1425);
FORCEPROP 1 LAST COMMENT_BODY TRUE
J 0
(1500 1450);
DISPLAY 0.872340 (1500 1450);
PAINT GREEN (1500 1450);
DISPLAY INVISIBLE (1500 1450);
FORCEPROP 2 LAST PATH I65
J 0
(1125 1600);
DISPLAY 0.680851 (1125 1600);
DISPLAY INVISIBLE (1125 1600);
FORCEADD OFFPAGE..1
(1375 1500);
FORCEPROP 2 LAST $XR0 287 
J 0
(1123 1500);
DISPLAY 0.638298 (1123 1500);
PAINT MONO (1123 1500);
FORCEPROP 2 LAST CDS_LIB standard
J 0
(1375 1500);
DISPLAY INVISIBLE (1375 1500);
FORCEPROP 1 LAST OFFPAGE TRUE
J 0
(1700 1375);
DISPLAY 0.872340 (1700 1375);
PAINT AQUA (1700 1375);
DISPLAY INVISIBLE (1700 1375);
FORCEPROP 1 LAST COMMENT_BODY TRUE
J 0
(1500 1400);
DISPLAY 0.872340 (1500 1400);
PAINT GREEN (1500 1400);
DISPLAY INVISIBLE (1500 1400);
FORCEPROP 2 LAST PATH I66
J 0
(1125 1550);
DISPLAY 0.680851 (1125 1550);
DISPLAY INVISIBLE (1125 1550);
FORCEADD OFFPAGE..1
(1375 1700);
FORCEPROP 2 LAST $XR0 276 
J 0
(1123 1700);
DISPLAY 0.638298 (1123 1700);
PAINT MONO (1123 1700);
FORCEPROP 2 LAST CDS_LIB standard
J 0
(1375 1700);
DISPLAY INVISIBLE (1375 1700);
FORCEPROP 1 LAST OFFPAGE TRUE
J 0
(1700 1575);
DISPLAY 0.872340 (1700 1575);
PAINT AQUA (1700 1575);
DISPLAY INVISIBLE (1700 1575);
FORCEPROP 1 LAST COMMENT_BODY TRUE
J 0
(1500 1600);
DISPLAY 0.872340 (1500 1600);
PAINT GREEN (1500 1600);
DISPLAY INVISIBLE (1500 1600);
FORCEPROP 2 LAST PATH I67
J 0
(1125 1750);
DISPLAY 0.680851 (1125 1750);
DISPLAY INVISIBLE (1125 1750);
FORCEADD OFFPAGE..5
(1375 1800);
FORCEPROP 2 LAST $XR0 286 
J 0
(1090 1800);
DISPLAY 0.638298 (1090 1800);
PAINT MONO (1090 1800);
FORCEPROP 2 LAST CDS_LIB standard
J 0
(1375 1800);
DISPLAY INVISIBLE (1375 1800);
FORCEPROP 1 LAST OFFPAGE TRUE
J 0
(1700 1675);
DISPLAY 0.872340 (1700 1675);
PAINT AQUA (1700 1675);
DISPLAY INVISIBLE (1700 1675);
FORCEPROP 1 LAST COMMENT_BODY TRUE
J 0
(1475 1725);
DISPLAY 1.170213 (1475 1725);
PAINT GREEN (1475 1725);
DISPLAY INVISIBLE (1475 1725);
FORCEPROP 2 LAST PATH I68
J 0
(1100 1850);
DISPLAY 0.680851 (1100 1850);
DISPLAY INVISIBLE (1100 1850);
FORCEADD OFFPAGE..2
R 2
(1375 1850);
FORCEPROP 2 LAST $XR0 286 
J 0
(1090 1850);
DISPLAY 0.638298 (1090 1850);
PAINT MONO (1090 1850);
FORCEPROP 2 LAST CDS_LIB standard
J 0
(1375 1850);
DISPLAY INVISIBLE (1375 1850);
FORCEPROP 1 LAST OFFPAGE TRUE
J 2
(1050 1725);
DISPLAY 0.872340 (1050 1725);
PAINT AQUA (1050 1725);
DISPLAY INVISIBLE (1050 1725);
FORCEPROP 1 LAST COMMENT_BODY TRUE
J 2
(1420 1755);
DISPLAY 0.872340 (1420 1755);
PAINT GREEN (1420 1755);
DISPLAY INVISIBLE (1420 1755);
FORCEPROP 2 LAST PATH I69
J 0
(1100 1900);
DISPLAY 0.680851 (1100 1900);
DISPLAY INVISIBLE (1100 1900);
FORCEADD OFFPAGE..5
(-3150 -450);
FORCEPROP 2 LAST $XR0 275 
J 0
(-3405 -450);
DISPLAY 0.638298 (-3405 -450);
PAINT MONO (-3405 -450);
FORCEPROP 2 LAST CDS_LIB standard
J 0
(-3150 -450);
DISPLAY INVISIBLE (-3150 -450);
FORCEPROP 1 LAST OFFPAGE TRUE
J 0
(-2825 -575);
DISPLAY 0.872340 (-2825 -575);
PAINT AQUA (-2825 -575);
DISPLAY INVISIBLE (-2825 -575);
FORCEPROP 1 LAST COMMENT_BODY TRUE
J 0
(-3050 -525);
DISPLAY 1.170213 (-3050 -525);
PAINT GREEN (-3050 -525);
DISPLAY INVISIBLE (-3050 -525);
FORCEPROP 2 LAST PATH I7
J 0
(-3425 -400);
DISPLAY 0.680851 (-3425 -400);
DISPLAY INVISIBLE (-3425 -400);
FORCEADD OFFPAGE..5
(1375 1950);
FORCEPROP 2 LAST $XR0 275 
J 0
(1090 1950);
DISPLAY 0.638298 (1090 1950);
PAINT MONO (1090 1950);
FORCEPROP 2 LAST CDS_LIB standard
J 0
(1375 1950);
DISPLAY INVISIBLE (1375 1950);
FORCEPROP 1 LAST OFFPAGE TRUE
J 0
(1700 1825);
DISPLAY 0.872340 (1700 1825);
PAINT AQUA (1700 1825);
DISPLAY INVISIBLE (1700 1825);
FORCEPROP 1 LAST COMMENT_BODY TRUE
J 0
(1475 1875);
DISPLAY 1.170213 (1475 1875);
PAINT GREEN (1475 1875);
DISPLAY INVISIBLE (1475 1875);
FORCEPROP 2 LAST PATH I70
J 0
(1100 2000);
DISPLAY 0.680851 (1100 2000);
DISPLAY INVISIBLE (1100 2000);
FORCEADD OFFPAGE..2
R 2
(1375 2000);
FORCEPROP 2 LAST $XR0 275 
J 0
(1090 2000);
DISPLAY 0.638298 (1090 2000);
PAINT MONO (1090 2000);
FORCEPROP 2 LAST CDS_LIB standard
J 0
(1375 2000);
DISPLAY INVISIBLE (1375 2000);
FORCEPROP 1 LAST OFFPAGE TRUE
J 2
(1050 1875);
DISPLAY 0.872340 (1050 1875);
PAINT AQUA (1050 1875);
DISPLAY INVISIBLE (1050 1875);
FORCEPROP 1 LAST COMMENT_BODY TRUE
J 2
(1420 1905);
DISPLAY 0.872340 (1420 1905);
PAINT GREEN (1420 1905);
DISPLAY INVISIBLE (1420 1905);
FORCEPROP 2 LAST PATH I71
J 0
(1100 2050);
DISPLAY 0.680851 (1100 2050);
DISPLAY INVISIBLE (1100 2050);
FORCEADD CONN112_10137002101LF..2
(3600 550);
FORCEPROP 1 LAST LOCATION J108
J 0
(2850 2375);
DISPLAY 0.723404 (2850 2375);
PAINT GREEN (2850 2375);
FORCEPROP 0 LAST $SEC 2
J 0
(2850 2500);
DISPLAY 0.680851 (2850 2500);
PAINT MONO (2850 2500);
DISPLAY INVISIBLE (2850 2500);
FORCEPROP 0 LAST CDS_SEC 2
J 0
(2850 2500);
DISPLAY 1.021277 (2850 2500);
DISPLAY INVISIBLE (2850 2500);
FORCEPROP 0 LASTPIN (2675 -350) $PN A1
J 2
(2665 -340);
DISPLAY 0.680851 (2665 -340);
PAINT MONO (2665 -340);
FORCEPROP 0 LASTPIN (2675 450) $PN A2
J 2
(2665 460);
DISPLAY 0.680851 (2665 460);
PAINT MONO (2665 460);
FORCEPROP 0 LASTPIN (2675 1250) $PN A3
J 2
(2665 1260);
DISPLAY 0.680851 (2665 1260);
PAINT MONO (2665 1260);
FORCEPROP 0 LASTPIN (2675 2050) $PN A4
J 2
(2665 2060);
DISPLAY 0.680851 (2665 2060);
PAINT MONO (2665 2060);
FORCEPROP 0 LASTPIN (2675 -400) $PN B1
J 2
(2665 -390);
DISPLAY 0.680851 (2665 -390);
PAINT MONO (2665 -390);
FORCEPROP 0 LASTPIN (2675 400) $PN B2
J 2
(2665 410);
DISPLAY 0.680851 (2665 410);
PAINT MONO (2665 410);
FORCEPROP 0 LASTPIN (2675 1200) $PN B3
J 2
(2665 1210);
DISPLAY 0.680851 (2665 1210);
PAINT MONO (2665 1210);
FORCEPROP 0 LASTPIN (2675 2000) $PN B4
J 2
(2665 2010);
DISPLAY 0.680851 (2665 2010);
PAINT MONO (2665 2010);
FORCEPROP 0 LASTPIN (2675 -450) $PN C1
J 2
(2665 -440);
DISPLAY 0.680851 (2665 -440);
PAINT MONO (2665 -440);
FORCEPROP 0 LASTPIN (2675 350) $PN C2
J 2
(2665 360);
DISPLAY 0.680851 (2665 360);
PAINT MONO (2665 360);
FORCEPROP 0 LASTPIN (2675 1150) $PN C3
J 2
(2665 1160);
DISPLAY 0.680851 (2665 1160);
PAINT MONO (2665 1160);
FORCEPROP 0 LASTPIN (2675 1950) $PN C4
J 2
(2665 1960);
DISPLAY 0.680851 (2665 1960);
PAINT MONO (2665 1960);
FORCEPROP 0 LASTPIN (2675 -500) $PN D1
J 2
(2665 -490);
DISPLAY 0.680851 (2665 -490);
PAINT MONO (2665 -490);
FORCEPROP 0 LASTPIN (2675 300) $PN D2
J 2
(2665 310);
DISPLAY 0.680851 (2665 310);
PAINT MONO (2665 310);
FORCEPROP 0 LASTPIN (2675 1100) $PN D3
J 2
(2665 1110);
DISPLAY 0.680851 (2665 1110);
PAINT MONO (2665 1110);
FORCEPROP 0 LASTPIN (2675 1900) $PN D4
J 2
(2665 1910);
DISPLAY 0.680851 (2665 1910);
PAINT MONO (2665 1910);
FORCEPROP 0 LASTPIN (2675 -550) $PN E1
J 2
(2665 -540);
DISPLAY 0.680851 (2665 -540);
PAINT MONO (2665 -540);
FORCEPROP 0 LASTPIN (2675 250) $PN E2
J 2
(2665 260);
DISPLAY 0.680851 (2665 260);
PAINT MONO (2665 260);
FORCEPROP 0 LASTPIN (2675 1050) $PN E3
J 2
(2665 1060);
DISPLAY 0.680851 (2665 1060);
PAINT MONO (2665 1060);
FORCEPROP 0 LASTPIN (2675 1850) $PN E4
J 2
(2665 1860);
DISPLAY 0.680851 (2665 1860);
PAINT MONO (2665 1860);
FORCEPROP 0 LASTPIN (2675 -600) $PN F1
J 2
(2665 -590);
DISPLAY 0.680851 (2665 -590);
PAINT MONO (2665 -590);
FORCEPROP 0 LASTPIN (2675 200) $PN F2
J 2
(2665 210);
DISPLAY 0.680851 (2665 210);
PAINT MONO (2665 210);
FORCEPROP 0 LASTPIN (2675 1000) $PN F3
J 2
(2665 1010);
DISPLAY 0.680851 (2665 1010);
PAINT MONO (2665 1010);
FORCEPROP 0 LASTPIN (2675 1800) $PN F4
J 2
(2665 1810);
DISPLAY 0.680851 (2665 1810);
PAINT MONO (2665 1810);
FORCEPROP 0 LASTPIN (2675 -650) $PN G1
J 2
(2665 -640);
DISPLAY 0.680851 (2665 -640);
PAINT MONO (2665 -640);
FORCEPROP 0 LASTPIN (2675 150) $PN G2
J 2
(2665 160);
DISPLAY 0.680851 (2665 160);
PAINT MONO (2665 160);
FORCEPROP 0 LASTPIN (2675 950) $PN G3
J 2
(2665 960);
DISPLAY 0.680851 (2665 960);
PAINT MONO (2665 960);
FORCEPROP 0 LASTPIN (2675 1750) $PN G4
J 2
(2665 1760);
DISPLAY 0.680851 (2665 1760);
PAINT MONO (2665 1760);
FORCEPROP 0 LASTPIN (2675 -700) $PN H1
J 2
(2665 -690);
DISPLAY 0.680851 (2665 -690);
PAINT MONO (2665 -690);
FORCEPROP 0 LASTPIN (2675 100) $PN H2
J 2
(2665 110);
DISPLAY 0.680851 (2665 110);
PAINT MONO (2665 110);
FORCEPROP 0 LASTPIN (2675 900) $PN H3
J 2
(2665 910);
DISPLAY 0.680851 (2665 910);
PAINT MONO (2665 910);
FORCEPROP 0 LASTPIN (2675 1700) $PN H4
J 2
(2665 1710);
DISPLAY 0.680851 (2665 1710);
PAINT MONO (2665 1710);
FORCEPROP 0 LASTPIN (2675 -750) $PN I1
J 2
(2665 -740);
DISPLAY 0.680851 (2665 -740);
PAINT MONO (2665 -740);
FORCEPROP 0 LASTPIN (2675 50) $PN I2
J 2
(2665 60);
DISPLAY 0.680851 (2665 60);
PAINT MONO (2665 60);
FORCEPROP 0 LASTPIN (2675 850) $PN I3
J 2
(2665 860);
DISPLAY 0.680851 (2665 860);
PAINT MONO (2665 860);
FORCEPROP 0 LASTPIN (2675 1650) $PN I4
J 2
(2665 1660);
DISPLAY 0.680851 (2665 1660);
PAINT MONO (2665 1660);
FORCEPROP 0 LASTPIN (2675 -800) $PN J1
J 2
(2665 -790);
DISPLAY 0.680851 (2665 -790);
PAINT MONO (2665 -790);
FORCEPROP 0 LASTPIN (2675 0) $PN J2
J 2
(2665 10);
DISPLAY 0.680851 (2665 10);
PAINT MONO (2665 10);
FORCEPROP 0 LASTPIN (2675 800) $PN J3
J 2
(2665 810);
DISPLAY 0.680851 (2665 810);
PAINT MONO (2665 810);
FORCEPROP 0 LASTPIN (2675 1600) $PN J4
J 2
(2665 1610);
DISPLAY 0.680851 (2665 1610);
PAINT MONO (2665 1610);
FORCEPROP 0 LASTPIN (2675 -850) $PN K1
J 2
(2665 -840);
DISPLAY 0.680851 (2665 -840);
PAINT MONO (2665 -840);
FORCEPROP 0 LASTPIN (2675 -50) $PN K2
J 2
(2665 -40);
DISPLAY 0.680851 (2665 -40);
PAINT MONO (2665 -40);
FORCEPROP 0 LASTPIN (2675 750) $PN K3
J 2
(2665 760);
DISPLAY 0.680851 (2665 760);
PAINT MONO (2665 760);
FORCEPROP 0 LASTPIN (2675 1550) $PN K4
J 2
(2665 1560);
DISPLAY 0.680851 (2665 1560);
PAINT MONO (2665 1560);
FORCEPROP 0 LASTPIN (2675 -900) $PN L1
J 2
(2665 -890);
DISPLAY 0.680851 (2665 -890);
PAINT MONO (2665 -890);
FORCEPROP 0 LASTPIN (2675 -100) $PN L2
J 2
(2665 -90);
DISPLAY 0.680851 (2665 -90);
PAINT MONO (2665 -90);
FORCEPROP 0 LASTPIN (2675 700) $PN L3
J 2
(2665 710);
DISPLAY 0.680851 (2665 710);
PAINT MONO (2665 710);
FORCEPROP 0 LASTPIN (2675 1500) $PN L4
J 2
(2665 1510);
DISPLAY 0.680851 (2665 1510);
PAINT MONO (2665 1510);
FORCEPROP 0 LASTPIN (2675 -950) $PN M1
J 2
(2665 -940);
DISPLAY 0.680851 (2665 -940);
PAINT MONO (2665 -940);
FORCEPROP 0 LASTPIN (2675 -150) $PN M2
J 2
(2665 -140);
DISPLAY 0.680851 (2665 -140);
PAINT MONO (2665 -140);
FORCEPROP 0 LASTPIN (2675 650) $PN M3
J 2
(2665 660);
DISPLAY 0.680851 (2665 660);
PAINT MONO (2665 660);
FORCEPROP 0 LASTPIN (2675 1450) $PN M4
J 2
(2665 1460);
DISPLAY 0.680851 (2665 1460);
PAINT MONO (2665 1460);
FORCEPROP 0 LASTPIN (2675 -1000) $PN N1
J 2
(2665 -990);
DISPLAY 0.680851 (2665 -990);
PAINT MONO (2665 -990);
FORCEPROP 0 LASTPIN (2675 -200) $PN N2
J 2
(2665 -190);
DISPLAY 0.680851 (2665 -190);
PAINT MONO (2665 -190);
FORCEPROP 0 LASTPIN (2675 600) $PN N3
J 2
(2665 610);
DISPLAY 0.680851 (2665 610);
PAINT MONO (2665 610);
FORCEPROP 0 LASTPIN (2675 1400) $PN N4
J 2
(2665 1410);
DISPLAY 0.680851 (2665 1410);
PAINT MONO (2665 1410);
FORCEPROP 2 LAST PART_TYPE THLF
J 0
(2850 2450);
DISPLAY 1.021277 (2850 2450);
FORCEPROP 1 LAST MATERIAL IO
J 0
(2858 2263);
DISPLAY 0.723404 (2858 2263);
PAINT GREEN (2858 2263);
FORCEPROP 1 LAST CDS_LMAN_SYM_OUTLINE -775,1650,775,-1650
J 0
(3600 550);
DISPLAY 0.468085 (3600 550);
PAINT GREEN (3600 550);
DISPLAY INVISIBLE (3600 550);
FORCEPROP 1 LAST NEEDS_NO_SIZE TRUE
J 0
(3600 550);
DISPLAY 0.723404 (3600 550);
PAINT GREEN (3600 550);
DISPLAY INVISIBLE (3600 550);
FORCEPROP 2 LAST CDS_LIB pure_quanta
J 0
(3600 550);
DISPLAY INVISIBLE (3600 550);
FORCEPROP 0 LAST VALUE CONN112_10137002-101LF
J 0
(2850 2450);
DISPLAY 1.021277 (2850 2450);
DISPLAY INVISIBLE (2850 2450);
FORCEPROP 1 LAST PATH I72
J 0
(3600 550);
DISPLAY 0.723404 (3600 550);
PAINT GREEN (3600 550);
DISPLAY INVISIBLE (3600 550);
FORCEPROP 1 LAST PART_NUMBER DFHSB2FR012
J 0
(2850 2325);
DISPLAY 0.723404 (2850 2325);
PAINT GREEN (2850 2325);
DISPLAY INVISIBLE (2850 2325);
FORCEADD OFFPAGE..2
R 2
(-3150 1450);
FORCEPROP 2 LAST $XR0 123 
J 0
(-3405 1450);
DISPLAY 0.638298 (-3405 1450);
PAINT MONO (-3405 1450);
FORCEPROP 2 LAST CDS_LIB standard
J 0
(-3150 1450);
DISPLAY INVISIBLE (-3150 1450);
FORCEPROP 1 LAST OFFPAGE TRUE
J 2
(-3475 1325);
DISPLAY 0.872340 (-3475 1325);
PAINT AQUA (-3475 1325);
DISPLAY INVISIBLE (-3475 1325);
FORCEPROP 1 LAST COMMENT_BODY TRUE
J 2
(-3105 1355);
DISPLAY 0.872340 (-3105 1355);
PAINT GREEN (-3105 1355);
DISPLAY INVISIBLE (-3105 1355);
FORCEPROP 2 LAST PATH I73
J 0
(-3100 1525);
DISPLAY 0.680851 (-3100 1525);
DISPLAY INVISIBLE (-3100 1525);
FORCEADD OFFPAGE..2
R 2
(-3150 -400);
FORCEPROP 2 LAST $XR0 275 
J 0
(-3405 -400);
DISPLAY 0.638298 (-3405 -400);
PAINT MONO (-3405 -400);
FORCEPROP 2 LAST CDS_LIB standard
J 0
(-3150 -400);
DISPLAY INVISIBLE (-3150 -400);
FORCEPROP 1 LAST OFFPAGE TRUE
J 2
(-3475 -525);
DISPLAY 0.872340 (-3475 -525);
PAINT AQUA (-3475 -525);
DISPLAY INVISIBLE (-3475 -525);
FORCEPROP 1 LAST COMMENT_BODY TRUE
J 2
(-3105 -495);
DISPLAY 0.872340 (-3105 -495);
PAINT GREEN (-3105 -495);
DISPLAY INVISIBLE (-3105 -495);
FORCEPROP 2 LAST PATH I8
J 0
(-3425 -350);
DISPLAY 0.680851 (-3425 -350);
DISPLAY INVISIBLE (-3425 -350);
FORCEADD OFFPAGE..2
R 2
(-3150 -300);
FORCEPROP 2 LAST $XR0 125 
J 0
(-3405 -300);
DISPLAY 0.638298 (-3405 -300);
PAINT MONO (-3405 -300);
FORCEPROP 2 LAST CDS_LIB standard
J 0
(-3150 -300);
DISPLAY INVISIBLE (-3150 -300);
FORCEPROP 1 LAST OFFPAGE TRUE
J 2
(-3475 -425);
DISPLAY 0.872340 (-3475 -425);
PAINT AQUA (-3475 -425);
DISPLAY INVISIBLE (-3475 -425);
FORCEPROP 1 LAST COMMENT_BODY TRUE
J 2
(-3105 -395);
DISPLAY 0.872340 (-3105 -395);
PAINT GREEN (-3105 -395);
DISPLAY INVISIBLE (-3105 -395);
FORCEPROP 2 LAST PATH I9
J 0
(-3425 -250);
DISPLAY 0.680851 (-3425 -250);
DISPLAY INVISIBLE (-3425 -250);
FORCEADD QUANTA_TITLE_BLOCK_C..1
(4725 -3300);
FORCEPROP 0 LAST CDS_CON_LAST_MODIFIED Thu Sep 14 16:12:58 2023
J 0
(2840 -3285);
PAINT MONO (2840 -3285);
DISPLAY INVISIBLE (2840 -3285);
FORCEPROP 2 LAST CUSTOM_TXT_CDS <XR_PAGE_TITLE>
J 0
(-3165 1950);
DISPLAY 0.638298 (-3165 1950);
PAINT PINK (-3165 1950);
DISPLAY INVISIBLE (-3165 1950);
FORCEPROP 2 LAST CUSTOM_TXT_CDS <CON_LAST_MODIFIED>
J 0
(2800 -3300);
DISPLAY 0.978723 (2800 -3300);
FORCEPROP 2 LAST CUSTOM_TXT_CDS <Q_PROJ>
J 0
(2343 -3198);
DISPLAY 1.212766 (2343 -3198);
FORCEPROP 2 LAST CUSTOM_TXT_CDS <NAME_1>
J 0
(1550 -3125);
FORCEPROP 2 LAST CUSTOM_TXT_CDS <NAME_2>
J 0
(1550 -3250);
FORCEPROP 2 LAST CUSTOM_TXT_CDS <Q_REV>
J 0
(4541 -3197);
DISPLAY 1.212766 (4541 -3197);
FORCEPROP 2 LAST CUSTOM_TXT_CDS <Q_NUMBER>
J 0
(3322 -3197);
DISPLAY 1.212766 (3322 -3197);
FORCEPROP 1 LAST CUSTOM_TXT_CDS <CON_PAGE_NUM> OF <CON_TOTAL_PAGES>
J 0
(4279 -3282);
DISPLAY 0.978723 (4279 -3282);
FORCEPROP 1 LAST Q_TITLE PCIE - CPU0_EXAMAX_P0/P1_X16
J 0
(-4550 -3250);
DISPLAY 1.957447 (-4550 -3250);
PAINT GREEN (-4550 -3250);
FORCEPROP 2 LAST CDS_LIB pure_quanta
J 0
(4725 -3300);
PAINT MONO (4725 -3300);
DISPLAY INVISIBLE (4725 -3300);
FORCEPROP 1 LAST CDS_LMAN_SYM_OUTLINE -9475,6775,100,-125
J 0
(4725 -3300);
DISPLAY 0.468085 (4725 -3300);
PAINT GREEN (4725 -3300);
DISPLAY INVISIBLE (4725 -3300);
FORCEPROP 2 LAST PAGE_BORDER TRUE
J 0
(-3165 1950);
DISPLAY 0.638298 (-3165 1950);
PAINT PINK (-3165 1950);
DISPLAY INVISIBLE (-3165 1950);
FORCEPROP 2 LAST CDS_XR_PAGE_TITLE CR-118 : @T6G_MB_LIB.T6G(SCH_1):PAGE118
J 0
(-3165 1950);
DISPLAY 0.638298 (-3165 1950);
PAINT PINK (-3165 1950);
DISPLAY INVISIBLE (-3165 1950);
FORCEPROP 1 LAST Q_DEPT BU9
J 1
(962 -3251);
DISPLAY 1.957447 (962 -3251);
PAINT GREEN (962 -3251);
DISPLAY INVISIBLE (962 -3251);
FORCEPROP 1 LAST COMMENT_BODY TRUE
J 0
(4737 -3313);
DISPLAY 0.978723 (4737 -3313);
PAINT GREEN (4737 -3313);
DISPLAY INVISIBLE (4737 -3313);
WIRE 16 -1 (-1875 -300)(-3100 -300);
FORCEPROP 2 LAST SIG_NAME GPU_3V3IO_RSVD5_FFU
J 0
(-2985 -290);
DISPLAY 0.638298 (-2985 -290);
WIRE 16 -1 (-1875 1450)(-3100 1450);
FORCEPROP 2 LAST SIG_NAME PRSNT_CABLE_GPU_A3_N
J 0
(-2985 1460);
DISPLAY 0.638298 (-2985 1460);
WIRE 16 -1 (-1875 2100)(-2050 2100);
WIRE 16 -1 (-2050 2100)(-2050 1950);
WIRE 16 -1 (-1875 1950)(-2050 1950);
WIRE 16 -1 (-2050 1950)(-2050 1800);
WIRE 16 -1 (-1875 1800)(-2050 1800);
WIRE 16 -1 (-2050 1800)(-2050 1650);
WIRE 16 -1 (-1875 1650)(-2050 1650);
WIRE 16 -1 (-2050 1650)(-2050 1500);
WIRE 16 -1 (-1875 1500)(-2050 1500);
WIRE 16 -1 (-2050 1500)(-2050 1250);
WIRE 16 -1 (-1875 1250)(-2050 1250);
WIRE 16 -1 (-2050 1250)(-2050 1100);
WIRE 16 -1 (-1875 1100)(-2050 1100);
WIRE 16 -1 (-2050 1100)(-2050 950);
WIRE 16 -1 (-1875 950)(-2050 950);
WIRE 16 -1 (-2050 950)(-2050 800);
WIRE 16 -1 (-1875 800)(-2050 800);
WIRE 16 -1 (-2050 800)(-2050 650);
WIRE 16 -1 (-1875 650)(-2050 650);
WIRE 16 -1 (-2050 650)(-2050 500);
WIRE 16 -1 (-1875 500)(-2050 500);
WIRE 16 -1 (-2050 500)(-2050 350);
WIRE 16 -1 (-1875 350)(-2050 350);
WIRE 16 -1 (-2050 350)(-2050 200);
WIRE 16 -1 (-1875 200)(-2050 200);
WIRE 16 -1 (-2050 200)(-2050 50);
WIRE 16 -1 (-1875 50)(-2050 50);
WIRE 16 -1 (-2050 50)(-2050 -100);
WIRE 16 -1 (-1875 -100)(-2050 -100);
WIRE 16 -1 (-2050 -100)(-2050 -350);
WIRE 16 -1 (-1875 -350)(-2050 -350);
WIRE 16 -1 (-2050 -500)(-2050 -350);
WIRE 16 -1 (-1875 -500)(-2050 -500);
WIRE 16 -1 (-2050 -650)(-2050 -500);
WIRE 16 -1 (-1875 -650)(-2050 -650);
WIRE 16 -1 (-2050 -650)(-2050 -800);
WIRE 16 -1 (-1875 -800)(-2050 -800);
WIRE 16 -1 (-2050 -800)(-2050 -950);
WIRE 16 -1 (-1875 -950)(-2050 -950);
WIRE 16 -1 (-2050 -950)(-2050 -1250);
WIRE 16 -1 (2675 2050)(2450 2050);
WIRE 16 -1 (2450 2050)(2450 1900);
WIRE 16 -1 (2675 1900)(2450 1900);
WIRE 16 -1 (2450 1900)(2450 1750);
WIRE 16 -1 (2675 1750)(2450 1750);
WIRE 16 -1 (2450 1750)(2450 1600);
WIRE 16 -1 (2675 1600)(2450 1600);
WIRE 16 -1 (2450 1600)(2450 1450);
WIRE 16 -1 (2675 1450)(2450 1450);
WIRE 16 -1 (2450 1450)(2450 1200);
WIRE 16 -1 (2675 1200)(2450 1200);
WIRE 16 -1 (2450 1200)(2450 1050);
WIRE 16 -1 (2675 1050)(2450 1050);
WIRE 16 -1 (2450 1050)(2450 900);
WIRE 16 -1 (2675 900)(2450 900);
WIRE 16 -1 (2450 900)(2450 750);
WIRE 16 -1 (2675 750)(2450 750);
WIRE 16 -1 (2450 750)(2450 600);
WIRE 16 -1 (2675 600)(2450 600);
WIRE 16 -1 (2450 600)(2450 450);
WIRE 16 -1 (2675 450)(2450 450);
WIRE 16 -1 (2450 450)(2450 300);
WIRE 16 -1 (2675 300)(2450 300);
WIRE 16 -1 (2450 300)(2450 150);
WIRE 16 -1 (2675 150)(2450 150);
WIRE 16 -1 (2450 150)(2450 0);
WIRE 16 -1 (2675 0)(2450 0);
WIRE 16 -1 (2450 0)(2450 -150);
WIRE 16 -1 (2675 -150)(2450 -150);
WIRE 16 -1 (2450 -150)(2450 -400);
WIRE 16 -1 (2675 -400)(2450 -400);
WIRE 16 -1 (2450 -400)(2450 -550);
WIRE 16 -1 (2675 -550)(2450 -550);
WIRE 16 -1 (2450 -550)(2450 -700);
WIRE 16 -1 (2675 -700)(2450 -700);
WIRE 16 -1 (2450 -700)(2450 -850);
WIRE 16 -1 (2675 -850)(2450 -850);
WIRE 16 -1 (2450 -850)(2450 -1000);
WIRE 16 -1 (2675 -1000)(2450 -1000);
WIRE 16 -1 (2450 -1000)(2450 -1350);
WIRE 16 -1 (-1875 1550)(-3100 1550);
FORCEPROP 2 LAST SIG_NAME P5E_CPU0_P1_TX_BUF_C_DP<7>
J 0
(-2985 1560);
DISPLAY 0.638298 (-2985 1560);
WIRE 16 -1 (-1875 1600)(-3100 1600);
FORCEPROP 2 LAST SIG_NAME P5E_CPU0_P1_TX_BUF_C_DN<7>
J 0
(-2985 1610);
DISPLAY 0.638298 (-2985 1610);
WIRE 16 -1 (-1875 1700)(-3100 1700);
FORCEPROP 2 LAST SIG_NAME P5E_CPU0_P0_TX_BUF_C_DP<7>
J 0
(-2985 1710);
DISPLAY 0.638298 (-2985 1710);
WIRE 16 -1 (-1875 1750)(-3100 1750);
FORCEPROP 2 LAST SIG_NAME P5E_CPU0_P0_TX_BUF_C_DN<7>
J 0
(-2985 1760);
DISPLAY 0.638298 (-2985 1760);
WIRE 16 -1 (-1875 1850)(-3100 1850);
FORCEPROP 2 LAST SIG_NAME P5E_CPU0_P1_RX_BUF_DP<7>
J 0
(-2985 1860);
DISPLAY 0.638298 (-2985 1860);
WIRE 16 -1 (-1875 1900)(-3100 1900);
FORCEPROP 2 LAST SIG_NAME P5E_CPU0_P1_RX_BUF_DN<7>
J 0
(-2985 1910);
DISPLAY 0.638298 (-2985 1910);
WIRE 16 -1 (-1875 2050)(-3100 2050);
FORCEPROP 2 LAST SIG_NAME P5E_CPU0_P0_RX_BUF_DN<7>
J 0
(-2985 2060);
DISPLAY 0.638298 (-2985 2060);
WIRE 16 -1 (-1875 2000)(-3100 2000);
FORCEPROP 2 LAST SIG_NAME P5E_CPU0_P0_RX_BUF_DP<7>
J 0
(-2985 2010);
DISPLAY 0.638298 (-2985 2010);
WIRE 16 -1 (2675 -200)(1450 -200);
FORCEPROP 2 LAST SIG_NAME NC_J108_N2
J 0
(1565 -190);
DISPLAY 0.638298 (1565 -190);
FORCEPROP 2 LASTPROP $XRERR UNIQUE?
J 0
(1210 -200);
DISPLAY 0.638298 (1210 -200);
PAINT MONO (1210 -200);
DISPLAY INVISIBLE (1210 -200);
WIRE 16 -1 (2675 -350)(1450 -350);
FORCEPROP 2 LAST SIG_NAME GPU_3V3IO_RSVD3_FFU
J 0
(1540 -340);
DISPLAY 0.638298 (1540 -340);
WIRE 16 -1 (2675 -450)(1425 -450);
FORCEPROP 2 LAST SIG_NAME P5E_CPU0_P0_RX_BUF_DN<0>
J 0
(1540 -440);
DISPLAY 0.638298 (1540 -440);
WIRE 16 -1 (2675 -650)(1425 -650);
FORCEPROP 2 LAST SIG_NAME P5E_CPU0_P1_RX_BUF_DP<0>
J 0
(1540 -640);
DISPLAY 0.638298 (1540 -640);
WIRE 16 -1 (2675 50)(1425 50);
FORCEPROP 2 LAST SIG_NAME P5E_CPU0_P0_TX_BUF_C_DP<1>
J 0
(1540 60);
DISPLAY 0.638298 (1540 60);
WIRE 16 -1 (2675 1950)(1425 1950);
FORCEPROP 2 LAST SIG_NAME P5E_CPU0_P0_RX_BUF_DP<3>
J 0
(1540 1960);
DISPLAY 0.638298 (1540 1960);
WIRE 16 -1 (-1875 1150)(-3100 1150);
FORCEPROP 2 LAST SIG_NAME P5E_CPU0_P0_RX_BUF_DP<6>
J 0
(-2985 1160);
DISPLAY 0.638298 (-2985 1160);
WIRE 16 -1 (-1875 850)(-3100 850);
FORCEPROP 2 LAST SIG_NAME P5E_CPU0_P0_TX_BUF_C_DP<6>
J 0
(-2985 860);
DISPLAY 0.638298 (-2985 860);
WIRE 16 -1 (-1875 700)(-3100 700);
FORCEPROP 2 LAST SIG_NAME P5E_CPU0_P1_TX_BUF_C_DP<6>
J 0
(-2985 710);
DISPLAY 0.638298 (-2985 710);
WIRE 16 -1 (2675 1250)(1450 1250);
FORCEPROP 2 LAST SIG_NAME PRSNT_CABLE_GPU_A2_N
J 0
(1540 1260);
DISPLAY 0.638298 (1540 1260);
WIRE 16 -1 (2675 1150)(1425 1150);
FORCEPROP 2 LAST SIG_NAME P5E_CPU0_P0_RX_BUF_DN<2>
J 0
(1540 1160);
DISPLAY 0.638298 (1540 1160);
WIRE 16 -1 (2675 1100)(1425 1100);
FORCEPROP 2 LAST SIG_NAME P5E_CPU0_P0_RX_BUF_DP<2>
J 0
(1540 1110);
DISPLAY 0.638298 (1540 1110);
WIRE 16 -1 (2675 1400)(1450 1400);
FORCEPROP 2 LAST SIG_NAME NC_J108_N4
J 0
(1565 1410);
DISPLAY 0.638298 (1565 1410);
FORCEPROP 2 LASTPROP $XRERR UNIQUE?
J 0
(1210 1400);
DISPLAY 0.638298 (1210 1400);
PAINT MONO (1210 1400);
DISPLAY INVISIBLE (1210 1400);
WIRE 16 -1 (2675 2000)(1425 2000);
FORCEPROP 2 LAST SIG_NAME P5E_CPU0_P0_RX_BUF_DN<3>
J 0
(1540 2010);
DISPLAY 0.638298 (1540 2010);
WIRE 16 -1 (2675 -900)(1425 -900);
FORCEPROP 2 LAST SIG_NAME P5E_CPU0_P1_TX_BUF_C_DN<0>
J 0
(1540 -890);
DISPLAY 0.638298 (1540 -890);
WIRE 16 -1 (2675 700)(1425 700);
FORCEPROP 2 LAST SIG_NAME P5E_CPU0_P1_TX_BUF_C_DN<2>
J 0
(1540 710);
DISPLAY 0.638298 (1540 710);
WIRE 16 -1 (-1875 -450)(-3100 -450);
FORCEPROP 2 LAST SIG_NAME P5E_CPU0_P0_RX_BUF_DP<4>
J 0
(-2985 -440);
DISPLAY 0.638298 (-2985 -440);
WIRE 16 -1 (-1875 -700)(-3100 -700);
FORCEPROP 2 LAST SIG_NAME P5E_CPU0_P0_TX_BUF_C_DN<4>
J 0
(-2985 -690);
DISPLAY 0.638298 (-2985 -690);
WIRE 16 -1 (-1875 -550)(-3100 -550);
FORCEPROP 2 LAST SIG_NAME P5E_CPU0_P1_RX_BUF_DN<4>
J 0
(-2985 -540);
DISPLAY 0.638298 (-2985 -540);
WIRE 16 -1 (-1875 -900)(-3100 -900);
FORCEPROP 2 LAST SIG_NAME P5E_CPU0_P1_TX_BUF_C_DP<4>
J 0
(-2985 -890);
DISPLAY 0.638298 (-2985 -890);
WIRE 16 -1 (-1875 -600)(-3100 -600);
FORCEPROP 2 LAST SIG_NAME P5E_CPU0_P1_RX_BUF_DP<4>
J 0
(-2985 -590);
DISPLAY 0.638298 (-2985 -590);
WIRE 16 -1 (-1875 -850)(-3100 -850);
FORCEPROP 2 LAST SIG_NAME P5E_CPU0_P1_TX_BUF_C_DN<4>
J 0
(-2985 -840);
DISPLAY 0.638298 (-2985 -840);
WIRE 16 -1 (-1875 -750)(-3100 -750);
FORCEPROP 2 LAST SIG_NAME P5E_CPU0_P0_TX_BUF_C_DP<4>
J 0
(-2985 -740);
DISPLAY 0.638298 (-2985 -740);
WIRE 16 -1 (-1875 150)(-3100 150);
FORCEPROP 2 LAST SIG_NAME P5E_CPU0_P0_TX_BUF_C_DN<5>
J 0
(-2985 160);
DISPLAY 0.638298 (-2985 160);
WIRE 16 -1 (-1875 -150)(-3100 -150);
FORCEPROP 2 LAST SIG_NAME NC_J108_N6
J 0
(-2985 -140);
DISPLAY 0.638298 (-2985 -140);
FORCEPROP 2 LASTPROP $XRERR UNIQUE?
J 0
(-3340 -150);
DISPLAY 0.638298 (-3340 -150);
PAINT MONO (-3340 -150);
DISPLAY INVISIBLE (-3340 -150);
WIRE 16 -1 (-1875 -400)(-3100 -400);
FORCEPROP 2 LAST SIG_NAME P5E_CPU0_P0_RX_BUF_DN<4>
J 0
(-2985 -390);
DISPLAY 0.638298 (-2985 -390);
WIRE 16 -1 (2675 -750)(1425 -750);
FORCEPROP 2 LAST SIG_NAME P5E_CPU0_P0_TX_BUF_C_DN<0>
J 0
(1540 -740);
DISPLAY 0.638298 (1540 -740);
WIRE 16 -1 (2675 -800)(1425 -800);
FORCEPROP 2 LAST SIG_NAME P5E_CPU0_P0_TX_BUF_C_DP<0>
J 0
(1540 -790);
DISPLAY 0.638298 (1540 -790);
WIRE 16 -1 (2675 -950)(1425 -950);
FORCEPROP 2 LAST SIG_NAME P5E_CPU0_P1_TX_BUF_C_DP<0>
J 0
(1540 -940);
DISPLAY 0.638298 (1540 -940);
WIRE 16 -1 (-1875 1300)(-3100 1300);
FORCEPROP 2 LAST SIG_NAME GPU_FPGA_OVERT_N
J 0
(-2985 1310);
DISPLAY 0.638298 (-2985 1310);
WIRE 16 -1 (-1875 1200)(-3100 1200);
FORCEPROP 2 LAST SIG_NAME P5E_CPU0_P0_RX_BUF_DN<6>
J 0
(-2985 1210);
DISPLAY 0.638298 (-2985 1210);
WIRE 16 -1 (-1875 1050)(-3100 1050);
FORCEPROP 2 LAST SIG_NAME P5E_CPU0_P1_RX_BUF_DN<6>
J 0
(-2985 1060);
DISPLAY 0.638298 (-2985 1060);
WIRE 16 -1 (-1875 1000)(-3100 1000);
FORCEPROP 2 LAST SIG_NAME P5E_CPU0_P1_RX_BUF_DP<6>
J 0
(-2985 1010);
DISPLAY 0.638298 (-2985 1010);
WIRE 16 -1 (-1875 900)(-3100 900);
FORCEPROP 2 LAST SIG_NAME P5E_CPU0_P0_TX_BUF_C_DN<6>
J 0
(-2985 910);
DISPLAY 0.638298 (-2985 910);
WIRE 16 -1 (-1875 750)(-3100 750);
FORCEPROP 2 LAST SIG_NAME P5E_CPU0_P1_TX_BUF_C_DN<6>
J 0
(-2985 760);
DISPLAY 0.638298 (-2985 760);
WIRE 16 -1 (-1875 450)(-3100 450);
FORCEPROP 2 LAST SIG_NAME P5E_CPU0_P0_RX_BUF_DN<5>
J 0
(-2985 460);
DISPLAY 0.638298 (-2985 460);
WIRE 16 -1 (-1875 400)(-3100 400);
FORCEPROP 2 LAST SIG_NAME P5E_CPU0_P0_RX_BUF_DP<5>
J 0
(-2985 410);
DISPLAY 0.638298 (-2985 410);
WIRE 16 -1 (-1875 300)(-3100 300);
FORCEPROP 2 LAST SIG_NAME P5E_CPU0_P1_RX_BUF_DN<5>
J 0
(-2985 310);
DISPLAY 0.638298 (-2985 310);
WIRE 16 -1 (-1875 250)(-3100 250);
FORCEPROP 2 LAST SIG_NAME P5E_CPU0_P1_RX_BUF_DP<5>
J 0
(-2985 260);
DISPLAY 0.638298 (-2985 260);
WIRE 16 -1 (-1875 100)(-3100 100);
FORCEPROP 2 LAST SIG_NAME P5E_CPU0_P0_TX_BUF_C_DP<5>
J 0
(-2985 110);
DISPLAY 0.638298 (-2985 110);
WIRE 16 -1 (-1875 0)(-3100 0);
FORCEPROP 2 LAST SIG_NAME P5E_CPU0_P1_TX_BUF_C_DN<5>
J 0
(-2985 10);
DISPLAY 0.638298 (-2985 10);
WIRE 16 -1 (-1875 -50)(-3100 -50);
FORCEPROP 2 LAST SIG_NAME P5E_CPU0_P1_TX_BUF_C_DP<5>
J 0
(-2985 -40);
DISPLAY 0.638298 (-2985 -40);
WIRE 16 -1 (2675 1700)(1425 1700);
FORCEPROP 2 LAST SIG_NAME P5E_CPU0_P0_TX_BUF_C_DN<3>
J 0
(1540 1710);
DISPLAY 0.638298 (1540 1710);
WIRE 16 -1 (2675 1850)(1425 1850);
FORCEPROP 2 LAST SIG_NAME P5E_CPU0_P1_RX_BUF_DN<3>
J 0
(1540 1860);
DISPLAY 0.638298 (1540 1860);
WIRE 16 -1 (2675 1800)(1425 1800);
FORCEPROP 2 LAST SIG_NAME P5E_CPU0_P1_RX_BUF_DP<3>
J 0
(1540 1810);
DISPLAY 0.638298 (1540 1810);
WIRE 16 -1 (2675 1650)(1425 1650);
FORCEPROP 2 LAST SIG_NAME P5E_CPU0_P0_TX_BUF_C_DP<3>
J 0
(1540 1660);
DISPLAY 0.638298 (1540 1660);
WIRE 16 -1 (2675 1550)(1425 1550);
FORCEPROP 2 LAST SIG_NAME P5E_CPU0_P1_TX_BUF_C_DN<3>
J 0
(1540 1560);
DISPLAY 0.638298 (1540 1560);
WIRE 16 -1 (2675 1500)(1425 1500);
FORCEPROP 2 LAST SIG_NAME P5E_CPU0_P1_TX_BUF_C_DP<3>
J 0
(1540 1510);
DISPLAY 0.638298 (1540 1510);
WIRE 16 -1 (2675 1000)(1425 1000);
FORCEPROP 2 LAST SIG_NAME P5E_CPU0_P1_RX_BUF_DN<2>
J 0
(1540 1010);
DISPLAY 0.638298 (1540 1010);
WIRE 16 -1 (2675 950)(1425 950);
FORCEPROP 2 LAST SIG_NAME P5E_CPU0_P1_RX_BUF_DP<2>
J 0
(1540 960);
DISPLAY 0.638298 (1540 960);
WIRE 16 -1 (2675 850)(1425 850);
FORCEPROP 2 LAST SIG_NAME P5E_CPU0_P0_TX_BUF_C_DN<2>
J 0
(1540 860);
DISPLAY 0.638298 (1540 860);
WIRE 16 -1 (2675 800)(1425 800);
FORCEPROP 2 LAST SIG_NAME P5E_CPU0_P0_TX_BUF_C_DP<2>
J 0
(1540 810);
DISPLAY 0.638298 (1540 810);
WIRE 16 -1 (2675 650)(1425 650);
FORCEPROP 2 LAST SIG_NAME P5E_CPU0_P1_TX_BUF_C_DP<2>
J 0
(1540 660);
DISPLAY 0.638298 (1540 660);
WIRE 16 -1 (2675 400)(1425 400);
FORCEPROP 2 LAST SIG_NAME P5E_CPU0_P0_RX_BUF_DN<1>
J 0
(1540 410);
DISPLAY 0.638298 (1540 410);
WIRE 16 -1 (2675 350)(1425 350);
FORCEPROP 2 LAST SIG_NAME P5E_CPU0_P0_RX_BUF_DP<1>
J 0
(1540 360);
DISPLAY 0.638298 (1540 360);
WIRE 16 -1 (2675 250)(1425 250);
FORCEPROP 2 LAST SIG_NAME P5E_CPU0_P1_RX_BUF_DN<1>
J 0
(1540 260);
DISPLAY 0.638298 (1540 260);
WIRE 16 -1 (2675 200)(1425 200);
FORCEPROP 2 LAST SIG_NAME P5E_CPU0_P1_RX_BUF_DP<1>
J 0
(1540 210);
DISPLAY 0.638298 (1540 210);
WIRE 16 -1 (2675 100)(1425 100);
FORCEPROP 2 LAST SIG_NAME P5E_CPU0_P0_TX_BUF_C_DN<1>
J 0
(1540 110);
DISPLAY 0.638298 (1540 110);
WIRE 16 -1 (2675 -50)(1425 -50);
FORCEPROP 2 LAST SIG_NAME P5E_CPU0_P1_TX_BUF_C_DN<1>
J 0
(1540 -40);
DISPLAY 0.638298 (1540 -40);
WIRE 16 -1 (2675 -100)(1425 -100);
FORCEPROP 2 LAST SIG_NAME P5E_CPU0_P1_TX_BUF_C_DP<1>
J 0
(1540 -90);
DISPLAY 0.638298 (1540 -90);
WIRE 16 -1 (2675 -500)(1425 -500);
FORCEPROP 2 LAST SIG_NAME P5E_CPU0_P0_RX_BUF_DP<0>
J 0
(1540 -490);
DISPLAY 0.638298 (1540 -490);
WIRE 16 -1 (2675 -600)(1425 -600);
FORCEPROP 2 LAST SIG_NAME P5E_CPU0_P1_RX_BUF_DN<0>
J 0
(1540 -590);
DISPLAY 0.638298 (1540 -590);
DOT 1 (-2050 1650);
DOT 1 (2450 300);
DOT 1 (2450 1200);
DOT 1 (-2050 -350);
DOT 1 (-2050 -100);
DOT 1 (-2050 50);
DOT 1 (-2050 200);
DOT 1 (-2050 350);
DOT 1 (-2050 1100);
DOT 1 (-2050 1250);
DOT 1 (-2050 800);
DOT 1 (-2050 950);
DOT 1 (2450 1900);
DOT 1 (2450 1750);
DOT 1 (2450 1600);
DOT 1 (2450 1450);
DOT 1 (2450 1050);
DOT 1 (2450 900);
DOT 1 (2450 750);
DOT 1 (2450 600);
DOT 1 (2450 450);
DOT 1 (2450 0);
DOT 1 (2450 150);
DOT 1 (2450 -400);
DOT 1 (2450 -550);
DOT 1 (2450 -700);
DOT 1 (2450 -850);
DOT 1 (2450 -1000);
DOT 1 (-2050 1800);
DOT 1 (-2050 1500);
DOT 1 (-2050 500);
DOT 1 (-2050 650);
DOT 1 (-2050 -500);
DOT 1 (-2050 -800);
DOT 1 (-2050 -650);
DOT 1 (-2050 -950);
DOT 1 (-2050 1950);
DOT 1 (2450 -150);
FORCENOTE
CPU0_P0_TX/RX<0-15> LANE REVERSAL
(-4425 2500) 0;
DISPLAY LEFT (-4425 2500);
DISPLAY 1.595745 (-4425 2500);
PAINT PINK (-4425 2500);
FORCENOTE
CPU0_P1_TX/RX<0-15> LANE REVERSAL
(-4425 2400) 0;
DISPLAY LEFT (-4425 2400);
DISPLAY 1.595745 (-4425 2400);
PAINT PINK (-4425 2400);
QUIT
